G04 ================== begin FILE IDENTIFICATION RECORD ==================*
G04 Layout Name:  13919-sa.brd*
G04 Film Name:    SE_REF_L4*
G04 File Format:  Gerber RS274X*
G04 File Origin:  Cadence Allegro 16.5-S039*
G04 Origin Date:  Fri Nov 22 15:27:08 2013*
G04 *
G04 Layer:  BOARD GEOMETRY/SE_REF_L4_TBL*
G04 Layer:  BOARD GEOMETRY/SE_REF_L4_BOTTOM*
G04 Layer:  BOARD GEOMETRY/PANEL_OUTLINE*
G04 *
G04 Offset:    (0.00 0.00)*
G04 Mirror:    No*
G04 Mode:      Positive*
G04 Rotation:  0*
G04 FullContactRelief:  No*
G04 UndefLineWidth:     6.00*
G04 ================== end FILE IDENTIFICATION RECORD ====================*
%FSLAX35Y35*MOIN*%
%IR0*IPPOS*OFA0.00000B0.00000*MIA0B0*SFA1.00000B1.00000*%
%ADD10C,.02*%
%ADD11C,.006*%
%ADD12C,.00425*%
G75*
%LPD*%
G75*
G54D10*
G01X825891Y587689D02*
X1333391D01*
G01X825891Y656989D02*
Y587689D01*
G01Y622339D02*
X1333391D01*
G01X825891Y656989D02*
X1333391D01*
G01X1000891D02*
Y587689D01*
G01X1228391Y656989D02*
Y587689D01*
G01X1333391Y656989D02*
Y587689D01*
G54D11*
G01X-14021Y-32800D02*
Y-50300D01*
G01X-19043Y-32800D02*
X-8999D01*
G01X-233Y-50300D02*
Y-32800D01*
G01Y-41258D02*
X859Y-39800D01*
X1951Y-38925D01*
X3697Y-38634D01*
X5007Y-38925D01*
X6536Y-40092D01*
X7191Y-41842D01*
Y-50300D01*
G01X20979Y-38634D02*
Y-50300D01*
G01Y-33967D02*
X20542Y-33675D01*
Y-33092D01*
X20979Y-32800D01*
X21416Y-33092D01*
Y-33675D01*
X20979Y-33967D01*
G01X35204Y-48259D02*
X36296Y-49425D01*
X37824Y-50300D01*
X39134D01*
X40444Y-49717D01*
X41317Y-48842D01*
X41754Y-47676D01*
X41536Y-45925D01*
X40662Y-45050D01*
X36732Y-43300D01*
X35859Y-41258D01*
X36296Y-39800D01*
X37169Y-38925D01*
X38479Y-38634D01*
X39789Y-38925D01*
X41099Y-39800D01*
G01X70422Y-54675D02*
X71951Y-55842D01*
X73697Y-56133D01*
X75225Y-55842D01*
X76536Y-54384D01*
X77409Y-52342D01*
Y-38634D01*
G01Y-40967D02*
X76536Y-39800D01*
X75225Y-38925D01*
X73697Y-38634D01*
X71951Y-39217D01*
X70859Y-40383D01*
X69985Y-42425D01*
X69549Y-44467D01*
X69767Y-46217D01*
X70641Y-48259D01*
X71951Y-49717D01*
X73697Y-50300D01*
X75007Y-50008D01*
X76536Y-48842D01*
X77409Y-47676D01*
G01X87704Y-42425D02*
X94691D01*
X94036Y-40383D01*
X92944Y-39217D01*
X91416Y-38634D01*
X89887Y-38925D01*
X88577Y-39800D01*
X87704Y-41842D01*
X87267Y-43592D01*
Y-45342D01*
X87704Y-47092D01*
X88796Y-48842D01*
X90106Y-50008D01*
X91634Y-50300D01*
X93162Y-49717D01*
X94691Y-47967D01*
G01X105422Y-50300D02*
Y-38634D01*
G01Y-40967D02*
X106514Y-39800D01*
X107606Y-38925D01*
X109134Y-38634D01*
X110225Y-38925D01*
X111536Y-39800D01*
G01X122049Y-50300D02*
Y-32800D01*
G01Y-41550D02*
X123141Y-39800D01*
X124451Y-38925D01*
X125761Y-38634D01*
X127725Y-39217D01*
X129036Y-40383D01*
X129909Y-42425D01*
Y-44758D01*
X129472Y-47092D01*
X128599Y-48842D01*
X127071Y-50008D01*
X125761Y-50300D01*
X124451Y-50008D01*
X123141Y-49134D01*
X122049Y-47676D01*
G01X140204Y-42425D02*
X147191D01*
X146536Y-40383D01*
X145444Y-39217D01*
X143916Y-38634D01*
X142387Y-38925D01*
X141077Y-39800D01*
X140204Y-41842D01*
X139767Y-43592D01*
Y-45342D01*
X140204Y-47092D01*
X141296Y-48842D01*
X142606Y-50008D01*
X144134Y-50300D01*
X145662Y-49717D01*
X147191Y-47967D01*
G01X157922Y-50300D02*
Y-38634D01*
G01Y-40967D02*
X159014Y-39800D01*
X160106Y-38925D01*
X161634Y-38634D01*
X162725Y-38925D01*
X164036Y-39800D01*
G01X195979Y-38634D02*
Y-50300D01*
G01Y-33967D02*
X195542Y-33675D01*
Y-33092D01*
X195979Y-32800D01*
X196416Y-33092D01*
Y-33675D01*
X195979Y-33967D01*
G01X210204Y-48259D02*
X211296Y-49425D01*
X212824Y-50300D01*
X214134D01*
X215444Y-49717D01*
X216317Y-48842D01*
X216754Y-47676D01*
X216536Y-45925D01*
X215662Y-45050D01*
X211732Y-43300D01*
X210859Y-41258D01*
X211296Y-39800D01*
X212169Y-38925D01*
X213479Y-38634D01*
X214789Y-38925D01*
X216099Y-39800D01*
G01X244985Y-54675D02*
X246514Y-55842D01*
X247824Y-56133D01*
X249571Y-55550D01*
X250881Y-54092D01*
X251536Y-51466D01*
Y-38634D01*
G01Y-33967D02*
X251099Y-33675D01*
Y-33092D01*
X251536Y-32800D01*
X251972Y-33092D01*
Y-33675D01*
X251536Y-33967D01*
G01X262267Y-38634D02*
Y-46800D01*
X263141Y-48842D01*
X264451Y-50008D01*
X265979Y-50300D01*
X267507Y-50008D01*
X268817Y-48842D01*
X269691Y-46800D01*
G01Y-50300D02*
Y-38634D01*
G01X280204Y-48259D02*
X281296Y-49425D01*
X282824Y-50300D01*
X284134D01*
X285444Y-49717D01*
X286317Y-48842D01*
X286754Y-47676D01*
X286536Y-45925D01*
X285662Y-45050D01*
X281732Y-43300D01*
X280859Y-41258D01*
X281296Y-39800D01*
X282169Y-38925D01*
X283479Y-38634D01*
X284789Y-38925D01*
X286099Y-39800D01*
G01X300979Y-32800D02*
Y-50300D01*
G01X297922Y-38634D02*
X304036D01*
G01X334669Y-50300D02*
Y-35425D01*
X335106Y-33967D01*
X335979Y-33092D01*
X337289Y-32800D01*
X338599Y-33383D01*
X339254Y-34842D01*
G01X336634Y-39800D02*
X332267D01*
G01X353479Y-50300D02*
X352169Y-50008D01*
X350859Y-48842D01*
X349985Y-46800D01*
X349549Y-44467D01*
X349985Y-42133D01*
X350859Y-40092D01*
X352169Y-38925D01*
X353479Y-38634D01*
X354789Y-38925D01*
X356099Y-40092D01*
X356972Y-42133D01*
X357191Y-44467D01*
X356972Y-46800D01*
X356099Y-48842D01*
X354789Y-50008D01*
X353479Y-50300D01*
G01X367922D02*
Y-38634D01*
G01Y-40967D02*
X369014Y-39800D01*
X370106Y-38925D01*
X371634Y-38634D01*
X372725Y-38925D01*
X374036Y-39800D01*
G01X401394Y-55550D02*
X402704Y-56133D01*
X404451Y-55550D01*
X405542Y-54384D01*
X406416Y-52925D01*
X407725Y-48259D01*
X410564Y-38634D01*
G01X403577D02*
X407725Y-48259D01*
G01X423479Y-50300D02*
X422169Y-50008D01*
X420859Y-48842D01*
X419985Y-46800D01*
X419549Y-44467D01*
X419985Y-42133D01*
X420859Y-40092D01*
X422169Y-38925D01*
X423479Y-38634D01*
X424789Y-38925D01*
X426099Y-40092D01*
X426972Y-42133D01*
X427191Y-44467D01*
X426972Y-46800D01*
X426099Y-48842D01*
X424789Y-50008D01*
X423479Y-50300D01*
G01X437267Y-38634D02*
Y-46800D01*
X438141Y-48842D01*
X439451Y-50008D01*
X440979Y-50300D01*
X442507Y-50008D01*
X443817Y-48842D01*
X444691Y-46800D01*
G01Y-50300D02*
Y-38634D01*
G01X455422Y-50300D02*
Y-38634D01*
G01Y-40967D02*
X456514Y-39800D01*
X457606Y-38925D01*
X459134Y-38634D01*
X460225Y-38925D01*
X461536Y-39800D01*
G01X490422Y-50300D02*
Y-38634D01*
G01Y-40967D02*
X491514Y-39800D01*
X492606Y-38925D01*
X494134Y-38634D01*
X495225Y-38925D01*
X496536Y-39800D01*
G01X507704Y-42425D02*
X514691D01*
X514036Y-40383D01*
X512944Y-39217D01*
X511416Y-38634D01*
X509887Y-38925D01*
X508577Y-39800D01*
X507704Y-41842D01*
X507267Y-43592D01*
Y-45342D01*
X507704Y-47092D01*
X508796Y-48842D01*
X510106Y-50008D01*
X511634Y-50300D01*
X513162Y-49717D01*
X514691Y-47967D01*
G01X527169Y-50300D02*
Y-35425D01*
X527606Y-33967D01*
X528479Y-33092D01*
X529789Y-32800D01*
X531099Y-33383D01*
X531754Y-34842D01*
G01X529134Y-39800D02*
X524767D01*
G01X542704Y-42425D02*
X549691D01*
X549036Y-40383D01*
X547944Y-39217D01*
X546416Y-38634D01*
X544887Y-38925D01*
X543577Y-39800D01*
X542704Y-41842D01*
X542267Y-43592D01*
Y-45342D01*
X542704Y-47092D01*
X543796Y-48842D01*
X545106Y-50008D01*
X546634Y-50300D01*
X548162Y-49717D01*
X549691Y-47967D01*
G01X560422Y-50300D02*
Y-38634D01*
G01Y-40967D02*
X561514Y-39800D01*
X562606Y-38925D01*
X564134Y-38634D01*
X565225Y-38925D01*
X566536Y-39800D01*
G01X577704Y-42425D02*
X584691D01*
X584036Y-40383D01*
X582944Y-39217D01*
X581416Y-38634D01*
X579887Y-38925D01*
X578577Y-39800D01*
X577704Y-41842D01*
X577267Y-43592D01*
Y-45342D01*
X577704Y-47092D01*
X578796Y-48842D01*
X580106Y-50008D01*
X581634Y-50300D01*
X583162Y-49717D01*
X584691Y-47967D01*
G01X594767Y-50300D02*
Y-38634D01*
G01Y-41550D02*
X595641Y-40092D01*
X596951Y-38925D01*
X598697Y-38634D01*
X600225Y-38925D01*
X601536Y-40092D01*
X602191Y-42133D01*
Y-50300D01*
G01X619472Y-40092D02*
X617944Y-38925D01*
X616634Y-38634D01*
X614887Y-39217D01*
X613577Y-40383D01*
X612704Y-42425D01*
X612485Y-44467D01*
X612704Y-46509D01*
X613577Y-48259D01*
X614887Y-49717D01*
X616634Y-50300D01*
X618162Y-49717D01*
X619472Y-48550D01*
G01X630204Y-42425D02*
X637191D01*
X636536Y-40383D01*
X635444Y-39217D01*
X633916Y-38634D01*
X632387Y-38925D01*
X631077Y-39800D01*
X630204Y-41842D01*
X629767Y-43592D01*
Y-45342D01*
X630204Y-47092D01*
X631296Y-48842D01*
X632606Y-50008D01*
X634134Y-50300D01*
X635662Y-49717D01*
X637191Y-47967D01*
G01X668479Y-32800D02*
Y-50300D01*
G01X665422Y-38634D02*
X671536D01*
G01X685979Y-50300D02*
X684669Y-50008D01*
X683359Y-48842D01*
X682485Y-46800D01*
X682049Y-44467D01*
X682485Y-42133D01*
X683359Y-40092D01*
X684669Y-38925D01*
X685979Y-38634D01*
X687289Y-38925D01*
X688599Y-40092D01*
X689472Y-42133D01*
X689691Y-44467D01*
X689472Y-46800D01*
X688599Y-48842D01*
X687289Y-50008D01*
X685979Y-50300D01*
G01X719669D02*
Y-35425D01*
X720106Y-33967D01*
X720979Y-33092D01*
X722289Y-32800D01*
X723599Y-33383D01*
X724254Y-34842D01*
G01X721634Y-39800D02*
X717267D01*
G01X738479Y-38634D02*
Y-50300D01*
G01Y-33967D02*
X738042Y-33675D01*
Y-33092D01*
X738479Y-32800D01*
X738916Y-33092D01*
Y-33675D01*
X738479Y-33967D01*
G01X752267Y-50300D02*
Y-38634D01*
G01Y-41550D02*
X753141Y-40092D01*
X754451Y-38925D01*
X756197Y-38634D01*
X757725Y-38925D01*
X759036Y-40092D01*
X759691Y-42133D01*
Y-50300D01*
G01X777409Y-32800D02*
Y-50300D01*
G01Y-47676D02*
X776536Y-49134D01*
X775225Y-50008D01*
X773697Y-50300D01*
X771951Y-49717D01*
X770641Y-48259D01*
X769767Y-46509D01*
X769549Y-44467D01*
X769767Y-42425D01*
X770641Y-40675D01*
X771951Y-39217D01*
X773697Y-38634D01*
X775225Y-38925D01*
X776317Y-39509D01*
X777409Y-40675D01*
G01X808479Y-32800D02*
Y-50300D01*
G01X805422Y-38634D02*
X811536D01*
G01X822267Y-50300D02*
Y-32800D01*
G01Y-41258D02*
X823359Y-39800D01*
X824451Y-38925D01*
X826197Y-38634D01*
X827507Y-38925D01*
X829036Y-40092D01*
X829691Y-41842D01*
Y-50300D01*
G01X840204Y-42425D02*
X847191D01*
X846536Y-40383D01*
X845444Y-39217D01*
X843916Y-38634D01*
X842387Y-38925D01*
X841077Y-39800D01*
X840204Y-41842D01*
X839767Y-43592D01*
Y-45342D01*
X840204Y-47092D01*
X841296Y-48842D01*
X842606Y-50008D01*
X844134Y-50300D01*
X845662Y-49717D01*
X847191Y-47967D01*
G01X873894D02*
X875641Y-49425D01*
X877606Y-50300D01*
X879352D01*
X881099Y-49425D01*
X882409Y-47967D01*
X883064Y-45925D01*
X882627Y-43884D01*
X881536Y-42133D01*
X879571Y-40967D01*
X876951Y-40383D01*
X875422Y-39217D01*
X874767Y-37175D01*
X875204Y-35133D01*
X876296Y-33675D01*
X877824Y-32800D01*
X879352D01*
X880881Y-33383D01*
X882191Y-34842D01*
G01X900346Y-50300D02*
X891612D01*
Y-32800D01*
X900346D01*
G01X896852Y-41258D02*
X891612D01*
G01X930979Y-38634D02*
Y-50300D01*
G01Y-33967D02*
X930542Y-33675D01*
Y-33092D01*
X930979Y-32800D01*
X931416Y-33092D01*
Y-33675D01*
X930979Y-33967D01*
G01X941929Y-50300D02*
Y-38634D01*
G01Y-41842D02*
X942584Y-40383D01*
X943676Y-39217D01*
X945204Y-38634D01*
X946732Y-39217D01*
X947824Y-40383D01*
X948479Y-41842D01*
Y-50300D01*
G01Y-41842D02*
X949134Y-40383D01*
X950225Y-39217D01*
X951754Y-38634D01*
X953282Y-39217D01*
X954374Y-40383D01*
X955029Y-42133D01*
Y-50300D01*
G01X962049Y-56133D02*
Y-38634D01*
G01Y-41258D02*
X963141Y-39800D01*
X964232Y-38925D01*
X965979Y-38634D01*
X967507Y-38925D01*
X969036Y-40383D01*
X969691Y-42425D01*
X969909Y-44467D01*
X969691Y-46509D01*
X969036Y-48550D01*
X967725Y-49717D01*
X965979Y-50300D01*
X964451Y-50008D01*
X962922Y-49134D01*
X962049Y-47967D01*
G01X980204Y-42425D02*
X987191D01*
X986536Y-40383D01*
X985444Y-39217D01*
X983916Y-38634D01*
X982387Y-38925D01*
X981077Y-39800D01*
X980204Y-41842D01*
X979767Y-43592D01*
Y-45342D01*
X980204Y-47092D01*
X981296Y-48842D01*
X982606Y-50008D01*
X984134Y-50300D01*
X985662Y-49717D01*
X987191Y-47967D01*
G01X1004909Y-32800D02*
Y-50300D01*
G01Y-47676D02*
X1004036Y-49134D01*
X1002725Y-50008D01*
X1001197Y-50300D01*
X999451Y-49717D01*
X998141Y-48259D01*
X997267Y-46509D01*
X997049Y-44467D01*
X997267Y-42425D01*
X998141Y-40675D01*
X999451Y-39217D01*
X1001197Y-38634D01*
X1002725Y-38925D01*
X1003817Y-39509D01*
X1004909Y-40675D01*
G01X1022409Y-50300D02*
Y-38634D01*
G01Y-40675D02*
X1021536Y-39509D01*
X1020225Y-38925D01*
X1018697Y-38634D01*
X1017169Y-39217D01*
X1015859Y-40383D01*
X1014985Y-42133D01*
X1014549Y-44467D01*
X1014985Y-46800D01*
X1015859Y-48550D01*
X1017169Y-49717D01*
X1018697Y-50300D01*
X1020225Y-50008D01*
X1021536Y-49134D01*
X1022409Y-47967D01*
G01X1032267Y-50300D02*
Y-38634D01*
G01Y-41550D02*
X1033141Y-40092D01*
X1034451Y-38925D01*
X1036197Y-38634D01*
X1037725Y-38925D01*
X1039036Y-40092D01*
X1039691Y-42133D01*
Y-50300D01*
G01X1056972Y-40092D02*
X1055444Y-38925D01*
X1054134Y-38634D01*
X1052387Y-39217D01*
X1051077Y-40383D01*
X1050204Y-42425D01*
X1049985Y-44467D01*
X1050204Y-46509D01*
X1051077Y-48259D01*
X1052387Y-49717D01*
X1054134Y-50300D01*
X1055662Y-49717D01*
X1056972Y-48550D01*
G01X1067704Y-42425D02*
X1074691D01*
X1074036Y-40383D01*
X1072944Y-39217D01*
X1071416Y-38634D01*
X1069887Y-38925D01*
X1068577Y-39800D01*
X1067704Y-41842D01*
X1067267Y-43592D01*
Y-45342D01*
X1067704Y-47092D01*
X1068796Y-48842D01*
X1070106Y-50008D01*
X1071634Y-50300D01*
X1073162Y-49717D01*
X1074691Y-47967D01*
G01X1105979Y-32800D02*
Y-50300D01*
G01X1102922Y-38634D02*
X1109036D01*
G01X1120422Y-50300D02*
Y-38634D01*
G01Y-40967D02*
X1121514Y-39800D01*
X1122606Y-38925D01*
X1124134Y-38634D01*
X1125225Y-38925D01*
X1126536Y-39800D01*
G01X1144909Y-50300D02*
Y-38634D01*
G01Y-40675D02*
X1144036Y-39509D01*
X1142725Y-38925D01*
X1141197Y-38634D01*
X1139669Y-39217D01*
X1138359Y-40383D01*
X1137485Y-42133D01*
X1137049Y-44467D01*
X1137485Y-46800D01*
X1138359Y-48550D01*
X1139669Y-49717D01*
X1141197Y-50300D01*
X1142725Y-50008D01*
X1144036Y-49134D01*
X1144909Y-47967D01*
G01X1161972Y-40092D02*
X1160444Y-38925D01*
X1159134Y-38634D01*
X1157387Y-39217D01*
X1156077Y-40383D01*
X1155204Y-42425D01*
X1154985Y-44467D01*
X1155204Y-46509D01*
X1156077Y-48259D01*
X1157387Y-49717D01*
X1159134Y-50300D01*
X1160662Y-49717D01*
X1161972Y-48550D01*
G01X1172704Y-42425D02*
X1179691D01*
X1179036Y-40383D01*
X1177944Y-39217D01*
X1176416Y-38634D01*
X1174887Y-38925D01*
X1173577Y-39800D01*
X1172704Y-41842D01*
X1172267Y-43592D01*
Y-45342D01*
X1172704Y-47092D01*
X1173796Y-48842D01*
X1175106Y-50008D01*
X1176634Y-50300D01*
X1178162Y-49717D01*
X1179691Y-47967D01*
G01X1190204Y-48259D02*
X1191296Y-49425D01*
X1192824Y-50300D01*
X1194134D01*
X1195444Y-49717D01*
X1196317Y-48842D01*
X1196754Y-47676D01*
X1196536Y-45925D01*
X1195662Y-45050D01*
X1191732Y-43300D01*
X1190859Y-41258D01*
X1191296Y-39800D01*
X1192169Y-38925D01*
X1193479Y-38634D01*
X1194789Y-38925D01*
X1196099Y-39800D01*
G01X1228479Y-38634D02*
Y-50300D01*
G01Y-33967D02*
X1228042Y-33675D01*
Y-33092D01*
X1228479Y-32800D01*
X1228916Y-33092D01*
Y-33675D01*
X1228479Y-33967D01*
G01X1242267Y-50300D02*
Y-38634D01*
G01Y-41550D02*
X1243141Y-40092D01*
X1244451Y-38925D01*
X1246197Y-38634D01*
X1247725Y-38925D01*
X1249036Y-40092D01*
X1249691Y-42133D01*
Y-50300D01*
G01X1280979D02*
Y-32800D01*
G01X1302409Y-50300D02*
Y-38634D01*
G01Y-40675D02*
X1301536Y-39509D01*
X1300225Y-38925D01*
X1298697Y-38634D01*
X1297169Y-39217D01*
X1295859Y-40383D01*
X1294985Y-42133D01*
X1294549Y-44467D01*
X1294985Y-46800D01*
X1295859Y-48550D01*
X1297169Y-49717D01*
X1298697Y-50300D01*
X1300225Y-50008D01*
X1301536Y-49134D01*
X1302409Y-47967D01*
G01X1311394Y-55550D02*
X1312704Y-56133D01*
X1314451Y-55550D01*
X1315542Y-54384D01*
X1316416Y-52925D01*
X1317725Y-48259D01*
X1320564Y-38634D01*
G01X1313577D02*
X1317725Y-48259D01*
G01X1330204Y-42425D02*
X1337191D01*
X1336536Y-40383D01*
X1335444Y-39217D01*
X1333916Y-38634D01*
X1332387Y-38925D01*
X1331077Y-39800D01*
X1330204Y-41842D01*
X1329767Y-43592D01*
Y-45342D01*
X1330204Y-47092D01*
X1331296Y-48842D01*
X1332606Y-50008D01*
X1334134Y-50300D01*
X1335662Y-49717D01*
X1337191Y-47967D01*
G01X1347922Y-50300D02*
Y-38634D01*
G01Y-40967D02*
X1349014Y-39800D01*
X1350106Y-38925D01*
X1351634Y-38634D01*
X1352725Y-38925D01*
X1354036Y-39800D01*
G01X1381612Y-32800D02*
Y-50300D01*
X1390346D01*
G01X1406099D02*
Y-32800D01*
X1398020Y-45342D01*
X1408938D01*
G01X1420979Y-50883D02*
X1420542Y-50592D01*
Y-50008D01*
X1420979Y-49717D01*
X1421416Y-50008D01*
Y-50592D01*
X1420979Y-50883D01*
G01X827856Y669072D02*
X829603Y667614D01*
X831568Y666739D01*
X833314D01*
X835061Y667614D01*
X836371Y669072D01*
X837026Y671114D01*
X836589Y673155D01*
X835498Y674906D01*
X833533Y676072D01*
X830913Y676656D01*
X829384Y677822D01*
X828729Y679864D01*
X829166Y681906D01*
X830258Y683364D01*
X831786Y684239D01*
X833314D01*
X834843Y683656D01*
X836153Y682197D01*
G01X854308Y666739D02*
X845574D01*
Y684239D01*
X854308D01*
G01X850814Y675781D02*
X845574D01*
G01X882321Y684239D02*
X887561D01*
G01X884941D02*
Y666739D01*
G01X882321D02*
X887561D01*
G01X896764D02*
Y684239D01*
X902441Y669656D01*
X908118Y684239D01*
Y666739D01*
G01X915574D02*
Y684239D01*
X920814D01*
X922561Y683364D01*
X923871Y681322D01*
X924308Y678989D01*
X923871Y676656D01*
X922779Y674906D01*
X920814Y674030D01*
X915574D01*
G01X941808Y666739D02*
X933074D01*
Y684239D01*
X941808D01*
G01X938314Y675781D02*
X933074D01*
G01X950138Y666739D02*
Y684239D01*
X954504D01*
X956251Y683364D01*
X957561Y682197D01*
X958653Y680448D01*
X959526Y678405D01*
X959744Y675489D01*
X959526Y672572D01*
X958653Y670530D01*
X957561Y668780D01*
X956251Y667614D01*
X954504Y666739D01*
X950138D01*
G01X966982D02*
X972441Y684239D01*
X977900Y666739D01*
G01X975934Y672864D02*
X968947D01*
G01X984919Y666739D02*
Y684239D01*
X994963Y666739D01*
Y684239D01*
G01X1012244Y682780D02*
X1010934Y683656D01*
X1009406Y684239D01*
X1007659D01*
X1005694Y683364D01*
X1004166Y681906D01*
X1003074Y680155D01*
X1002201Y677239D01*
X1001982Y674614D01*
X1002419Y671989D01*
X1003074Y670239D01*
X1004384Y668489D01*
X1005913Y667322D01*
X1007441Y666739D01*
X1008969D01*
X1010498Y667322D01*
X1011808Y668197D01*
X1012900Y669363D01*
G01X1029308Y666739D02*
X1020574D01*
Y684239D01*
X1029308D01*
G01X1025814Y675781D02*
X1020574D01*
G01X1059941Y684239D02*
Y666739D01*
G01X1054919Y684239D02*
X1064963D01*
G01X1071982Y666739D02*
X1077441Y684239D01*
X1082900Y666739D01*
G01X1080934Y672864D02*
X1073947D01*
G01X1096687Y676072D02*
X1097561Y676947D01*
X1098216Y678405D01*
X1098653Y680448D01*
X1098216Y682197D01*
X1097343Y683364D01*
X1095814Y684239D01*
X1089919D01*
Y666739D01*
X1097124D01*
X1098653Y667905D01*
X1099526Y669656D01*
X1099963Y671697D01*
X1099526Y673739D01*
X1098216Y675489D01*
X1096687Y676072D01*
X1089919D01*
G01X1108074Y684239D02*
Y666739D01*
X1116808D01*
G01X1134308D02*
X1125574D01*
Y684239D01*
X1134308D01*
G01X1130814Y675781D02*
X1125574D01*
G01X1147441Y666156D02*
X1147004Y666447D01*
Y667031D01*
X1147441Y667322D01*
X1147878Y667031D01*
Y666447D01*
X1147441Y666156D01*
G01Y674030D02*
X1147004Y674322D01*
Y674906D01*
X1147441Y675197D01*
X1147878Y674906D01*
Y674322D01*
X1147441Y674030D01*
G01X1178074Y684239D02*
Y666739D01*
X1186808D01*
G01X1202561D02*
Y684239D01*
X1194482Y671697D01*
X1205400D01*
G01X849521Y649589D02*
X854761D01*
G01X852141D02*
Y632089D01*
G01X849521D02*
X854761D01*
G01X863964D02*
Y649589D01*
X869641Y635006D01*
X875318Y649589D01*
Y632089D01*
G01X882774D02*
Y649589D01*
X888014D01*
X889761Y648714D01*
X891071Y646672D01*
X891508Y644339D01*
X891071Y642006D01*
X889979Y640256D01*
X888014Y639380D01*
X882774D01*
G01X903549Y626256D02*
X901366Y629172D01*
X900274Y632089D01*
Y643755D01*
X901366Y646672D01*
X903549Y649589D01*
G01X922141Y632089D02*
X920394Y632381D01*
X918866Y633547D01*
X917556Y635297D01*
X916682Y637339D01*
X916246Y639672D01*
Y642006D01*
X916682Y644339D01*
X917556Y646381D01*
X918866Y648130D01*
X920394Y649297D01*
X922141Y649589D01*
X923887Y649297D01*
X925416Y648130D01*
X926726Y646381D01*
X927600Y644339D01*
X928036Y642006D01*
Y639672D01*
X927600Y637339D01*
X926726Y635297D01*
X925416Y633547D01*
X923887Y632381D01*
X922141Y632089D01*
G01X935929D02*
Y649589D01*
G01Y641131D02*
X937021Y642589D01*
X938113Y643464D01*
X939859Y643755D01*
X941169Y643464D01*
X942698Y642297D01*
X943353Y640547D01*
Y632089D01*
G01X950591D02*
Y643755D01*
G01Y640547D02*
X951246Y642006D01*
X952338Y643172D01*
X953866Y643755D01*
X955394Y643172D01*
X956486Y642006D01*
X957141Y640547D01*
Y632089D01*
G01Y640547D02*
X957796Y642006D01*
X958887Y643172D01*
X960416Y643755D01*
X961944Y643172D01*
X963036Y642006D01*
X963691Y640256D01*
Y632089D01*
G01X975733Y626256D02*
X977916Y629172D01*
X979008Y632089D01*
Y643755D01*
X977916Y646672D01*
X975733Y649589D01*
G01X882338Y600063D02*
X883647Y598605D01*
X885176Y597731D01*
X887141Y597439D01*
X889106Y598022D01*
X890634Y599189D01*
X891726Y601230D01*
X891944Y603564D01*
X891508Y605897D01*
X890416Y607356D01*
X888887Y608522D01*
X887359Y608814D01*
X885831Y608522D01*
X883866Y607356D01*
X884521Y614939D01*
X890416D01*
G01X904641D02*
X902894Y614356D01*
X901584Y612897D01*
X900711Y611148D01*
X900056Y608814D01*
X899838Y606189D01*
X900056Y603564D01*
X900711Y601230D01*
X901584Y599480D01*
X902894Y598022D01*
X904641Y597439D01*
X906387Y598022D01*
X907698Y599480D01*
X908571Y601230D01*
X909226Y603564D01*
X909444Y606189D01*
X909226Y608814D01*
X908571Y611148D01*
X907698Y612897D01*
X906387Y614356D01*
X904641Y614939D01*
G01X922141Y596856D02*
X921704Y597147D01*
Y597731D01*
X922141Y598022D01*
X922578Y597731D01*
Y597147D01*
X922141Y596856D01*
G01X939641Y614939D02*
X937894Y614356D01*
X936584Y612897D01*
X935711Y611148D01*
X935056Y608814D01*
X934838Y606189D01*
X935056Y603564D01*
X935711Y601230D01*
X936584Y599480D01*
X937894Y598022D01*
X939641Y597439D01*
X941387Y598022D01*
X942698Y599480D01*
X943571Y601230D01*
X944226Y603564D01*
X944444Y606189D01*
X944226Y608814D01*
X943571Y611148D01*
X942698Y612897D01*
X941387Y614356D01*
X939641Y614939D01*
G01X1020591Y649589D02*
X1023647Y632089D01*
X1027141Y649589D01*
X1030634Y632089D01*
X1033691Y649589D01*
G01X1042021D02*
X1047261D01*
G01X1044641D02*
Y632089D01*
G01X1042021D02*
X1047261D01*
G01X1057338D02*
Y649589D01*
X1061704D01*
X1063451Y648714D01*
X1064761Y647547D01*
X1065853Y645798D01*
X1066726Y643755D01*
X1066944Y640839D01*
X1066726Y637922D01*
X1065853Y635880D01*
X1064761Y634130D01*
X1063451Y632964D01*
X1061704Y632089D01*
X1057338D01*
G01X1079641Y649589D02*
Y632089D01*
G01X1074619Y649589D02*
X1084663D01*
G01X1092556Y632089D02*
Y649589D01*
G01X1101726D02*
Y632089D01*
G01Y640839D02*
X1092556D01*
G01X1113549Y626256D02*
X1111366Y629172D01*
X1110274Y632089D01*
Y643755D01*
X1111366Y646672D01*
X1113549Y649589D01*
G01X1125591Y632089D02*
Y643755D01*
G01Y640547D02*
X1126246Y642006D01*
X1127338Y643172D01*
X1128866Y643755D01*
X1130394Y643172D01*
X1131486Y642006D01*
X1132141Y640547D01*
Y632089D01*
G01Y640547D02*
X1132796Y642006D01*
X1133887Y643172D01*
X1135416Y643755D01*
X1136944Y643172D01*
X1138036Y642006D01*
X1138691Y640256D01*
Y632089D01*
G01X1149641Y643755D02*
Y632089D01*
G01Y648422D02*
X1149204Y648714D01*
Y649297D01*
X1149641Y649589D01*
X1150078Y649297D01*
Y648714D01*
X1149641Y648422D01*
G01X1167141Y632089D02*
Y649589D01*
G01X1181366Y634130D02*
X1182458Y632964D01*
X1183986Y632089D01*
X1185296D01*
X1186606Y632672D01*
X1187479Y633547D01*
X1187916Y634713D01*
X1187698Y636464D01*
X1186824Y637339D01*
X1182894Y639089D01*
X1182021Y641131D01*
X1182458Y642589D01*
X1183331Y643464D01*
X1184641Y643755D01*
X1185951Y643464D01*
X1187261Y642589D01*
G01X1203233Y626256D02*
X1205416Y629172D01*
X1206508Y632089D01*
Y643755D01*
X1205416Y646672D01*
X1203233Y649589D01*
G01X1091011Y597439D02*
Y614939D01*
X1082932Y602397D01*
X1093850D01*
G01X1105891Y596856D02*
X1105454Y597147D01*
Y597731D01*
X1105891Y598022D01*
X1106328Y597731D01*
Y597147D01*
X1105891Y596856D01*
G01X1119243Y612022D02*
X1120553Y613772D01*
X1122081Y614647D01*
X1123828Y614939D01*
X1126011Y614356D01*
X1127539Y612897D01*
X1127976Y611148D01*
X1127758Y609397D01*
X1126884Y607939D01*
X1122518Y605022D01*
X1120553Y602981D01*
X1119243Y600063D01*
X1118806Y597439D01*
X1127976D01*
G01X1136088Y600063D02*
X1137397Y598605D01*
X1138926Y597731D01*
X1140891Y597439D01*
X1142856Y598022D01*
X1144384Y599189D01*
X1145476Y601230D01*
X1145694Y603564D01*
X1145258Y605897D01*
X1144166Y607356D01*
X1142637Y608522D01*
X1141109Y608814D01*
X1139581Y608522D01*
X1137616Y607356D01*
X1138271Y614939D01*
X1144166D01*
G01X1254641Y649589D02*
Y632089D01*
G01X1249619Y649589D02*
X1259663D01*
G01X1272141Y632089D02*
Y639964D01*
X1267774Y649589D01*
G01X1276508D02*
X1272141Y639964D01*
G01X1285274Y632089D02*
Y649589D01*
X1290514D01*
X1292261Y648714D01*
X1293571Y646672D01*
X1294008Y644339D01*
X1293571Y642006D01*
X1292479Y640256D01*
X1290514Y639380D01*
X1285274D01*
G01X1311508Y632089D02*
X1302774D01*
Y649589D01*
X1311508D01*
G01X1308014Y641131D02*
X1302774D01*
G01X1267556Y599772D02*
X1269303Y598314D01*
X1271268Y597439D01*
X1273014D01*
X1274761Y598314D01*
X1276071Y599772D01*
X1276726Y601814D01*
X1276289Y603855D01*
X1275198Y605606D01*
X1273233Y606772D01*
X1270613Y607356D01*
X1269084Y608522D01*
X1268429Y610564D01*
X1268866Y612606D01*
X1269958Y614064D01*
X1271486Y614939D01*
X1273014D01*
X1274543Y614356D01*
X1275853Y612897D01*
G01X1294008Y597439D02*
X1285274D01*
Y614939D01*
X1294008D01*
G01X1290514Y606481D02*
X1285274D01*
G01X1459941Y574455D02*
Y562789D01*
G01Y579122D02*
X1459504Y579414D01*
Y579997D01*
X1459941Y580289D01*
X1460378Y579997D01*
Y579414D01*
X1459941Y579122D01*
G01X1473729Y562789D02*
Y574455D01*
G01Y571539D02*
X1474603Y572997D01*
X1475913Y574164D01*
X1477659Y574455D01*
X1479187Y574164D01*
X1480498Y572997D01*
X1481153Y570956D01*
Y562789D01*
G01X1491666Y564830D02*
X1492758Y563664D01*
X1494286Y562789D01*
X1495596D01*
X1496906Y563372D01*
X1497779Y564247D01*
X1498216Y565413D01*
X1497998Y567164D01*
X1497124Y568039D01*
X1493194Y569789D01*
X1492321Y571831D01*
X1492758Y573289D01*
X1493631Y574164D01*
X1494941Y574455D01*
X1496251Y574164D01*
X1497561Y573289D01*
G01X1512441Y574455D02*
Y562789D01*
G01Y579122D02*
X1512004Y579414D01*
Y579997D01*
X1512441Y580289D01*
X1512878Y579997D01*
Y579414D01*
X1512441Y579122D01*
G01X1533871Y580289D02*
Y562789D01*
G01Y565413D02*
X1532998Y563955D01*
X1531687Y563081D01*
X1530159Y562789D01*
X1528413Y563372D01*
X1527103Y564830D01*
X1526229Y566580D01*
X1526011Y568622D01*
X1526229Y570664D01*
X1527103Y572414D01*
X1528413Y573872D01*
X1530159Y574455D01*
X1531687Y574164D01*
X1532779Y573580D01*
X1533871Y572414D01*
G01X1544166Y570664D02*
X1551153D01*
X1550498Y572706D01*
X1549406Y573872D01*
X1547878Y574455D01*
X1546349Y574164D01*
X1545039Y573289D01*
X1544166Y571247D01*
X1543729Y569497D01*
Y567747D01*
X1544166Y565997D01*
X1545258Y564247D01*
X1546568Y563081D01*
X1548096Y562789D01*
X1549624Y563372D01*
X1551153Y565122D01*
G01X1578511Y562789D02*
Y580289D01*
G01Y571539D02*
X1579603Y573289D01*
X1580913Y574164D01*
X1582223Y574455D01*
X1584187Y573872D01*
X1585498Y572706D01*
X1586371Y570664D01*
Y568331D01*
X1585934Y565997D01*
X1585061Y564247D01*
X1583533Y563081D01*
X1582223Y562789D01*
X1580913Y563081D01*
X1579603Y563955D01*
X1578511Y565413D01*
G01X1599941Y562789D02*
X1598631Y563081D01*
X1597321Y564247D01*
X1596447Y566289D01*
X1596011Y568622D01*
X1596447Y570956D01*
X1597321Y572997D01*
X1598631Y574164D01*
X1599941Y574455D01*
X1601251Y574164D01*
X1602561Y572997D01*
X1603434Y570956D01*
X1603653Y568622D01*
X1603434Y566289D01*
X1602561Y564247D01*
X1601251Y563081D01*
X1599941Y562789D01*
G01X1621371D02*
Y574455D01*
G01Y572414D02*
X1620498Y573580D01*
X1619187Y574164D01*
X1617659Y574455D01*
X1616131Y573872D01*
X1614821Y572706D01*
X1613947Y570956D01*
X1613511Y568622D01*
X1613947Y566289D01*
X1614821Y564539D01*
X1616131Y563372D01*
X1617659Y562789D01*
X1619187Y563081D01*
X1620498Y563955D01*
X1621371Y565122D01*
G01X1631884Y562789D02*
Y574455D01*
G01Y572122D02*
X1632976Y573289D01*
X1634068Y574164D01*
X1635596Y574455D01*
X1636687Y574164D01*
X1637998Y573289D01*
G01X1656371Y580289D02*
Y562789D01*
G01Y565413D02*
X1655498Y563955D01*
X1654187Y563081D01*
X1652659Y562789D01*
X1650913Y563372D01*
X1649603Y564830D01*
X1648729Y566580D01*
X1648511Y568622D01*
X1648729Y570664D01*
X1649603Y572414D01*
X1650913Y573872D01*
X1652659Y574455D01*
X1654187Y574164D01*
X1655279Y573580D01*
X1656371Y572414D01*
G01X1687441Y562789D02*
X1686131Y563081D01*
X1684821Y564247D01*
X1683947Y566289D01*
X1683511Y568622D01*
X1683947Y570956D01*
X1684821Y572997D01*
X1686131Y574164D01*
X1687441Y574455D01*
X1688751Y574164D01*
X1690061Y572997D01*
X1690934Y570956D01*
X1691153Y568622D01*
X1690934Y566289D01*
X1690061Y564247D01*
X1688751Y563081D01*
X1687441Y562789D01*
G01X1701229Y574455D02*
Y566289D01*
X1702103Y564247D01*
X1703413Y563081D01*
X1704941Y562789D01*
X1706469Y563081D01*
X1707779Y564247D01*
X1708653Y566289D01*
G01Y562789D02*
Y574455D01*
G01X1722441Y580289D02*
Y562789D01*
G01X1719384Y574455D02*
X1725498D01*
G01X1739941Y562789D02*
Y580289D01*
G01X1757441Y574455D02*
Y562789D01*
G01Y579122D02*
X1757004Y579414D01*
Y579997D01*
X1757441Y580289D01*
X1757878Y579997D01*
Y579414D01*
X1757441Y579122D01*
G01X1771229Y562789D02*
Y574455D01*
G01Y571539D02*
X1772103Y572997D01*
X1773413Y574164D01*
X1775159Y574455D01*
X1776687Y574164D01*
X1777998Y572997D01*
X1778653Y570956D01*
Y562789D01*
G01X1789166Y570664D02*
X1796153D01*
X1795498Y572706D01*
X1794406Y573872D01*
X1792878Y574455D01*
X1791349Y574164D01*
X1790039Y573289D01*
X1789166Y571247D01*
X1788729Y569497D01*
Y567747D01*
X1789166Y565997D01*
X1790258Y564247D01*
X1791568Y563081D01*
X1793096Y562789D01*
X1794624Y563372D01*
X1796153Y565122D01*
G01X1809941Y562206D02*
X1809504Y562497D01*
Y563081D01*
X1809941Y563372D01*
X1810378Y563081D01*
Y562497D01*
X1809941Y562206D01*
G01X1385138Y631506D02*
X1394744Y644339D01*
G01X1389941Y646672D02*
Y629172D01*
G01X1394744Y631506D02*
X1385138Y644339D01*
G01X1383391Y637922D02*
X1396491D01*
G01X1422103D02*
X1427779D01*
G01X1455138Y632089D02*
Y649589D01*
X1459504D01*
X1461251Y648714D01*
X1462561Y647547D01*
X1463653Y645798D01*
X1464526Y643755D01*
X1464744Y640839D01*
X1464526Y637922D01*
X1463653Y635880D01*
X1462561Y634130D01*
X1461251Y632964D01*
X1459504Y632089D01*
X1455138D01*
G01X1474166Y639964D02*
X1481153D01*
X1480498Y642006D01*
X1479406Y643172D01*
X1477878Y643755D01*
X1476349Y643464D01*
X1475039Y642589D01*
X1474166Y640547D01*
X1473729Y638797D01*
Y637047D01*
X1474166Y635297D01*
X1475258Y633547D01*
X1476568Y632381D01*
X1478096Y632089D01*
X1479624Y632672D01*
X1481153Y634422D01*
G01X1491229Y632089D02*
Y643755D01*
G01Y640839D02*
X1492103Y642297D01*
X1493413Y643464D01*
X1495159Y643755D01*
X1496687Y643464D01*
X1497998Y642297D01*
X1498653Y640256D01*
Y632089D01*
G01X1512441D02*
X1511131Y632381D01*
X1509821Y633547D01*
X1508947Y635589D01*
X1508511Y637922D01*
X1508947Y640256D01*
X1509821Y642297D01*
X1511131Y643464D01*
X1512441Y643755D01*
X1513751Y643464D01*
X1515061Y642297D01*
X1515934Y640256D01*
X1516153Y637922D01*
X1515934Y635589D01*
X1515061Y633547D01*
X1513751Y632381D01*
X1512441Y632089D01*
G01X1529941Y649589D02*
Y632089D01*
G01X1526884Y643755D02*
X1532998D01*
G01X1544166Y639964D02*
X1551153D01*
X1550498Y642006D01*
X1549406Y643172D01*
X1547878Y643755D01*
X1546349Y643464D01*
X1545039Y642589D01*
X1544166Y640547D01*
X1543729Y638797D01*
Y637047D01*
X1544166Y635297D01*
X1545258Y633547D01*
X1546568Y632381D01*
X1548096Y632089D01*
X1549624Y632672D01*
X1551153Y634422D01*
G01X1561666Y634130D02*
X1562758Y632964D01*
X1564286Y632089D01*
X1565596D01*
X1566906Y632672D01*
X1567779Y633547D01*
X1568216Y634713D01*
X1567998Y636464D01*
X1567124Y637339D01*
X1563194Y639089D01*
X1562321Y641131D01*
X1562758Y642589D01*
X1563631Y643464D01*
X1564941Y643755D01*
X1566251Y643464D01*
X1567561Y642589D01*
G01X1599941Y649589D02*
Y632089D01*
G01X1596884Y643755D02*
X1602998D01*
G01X1613729Y632089D02*
Y649589D01*
G01Y641131D02*
X1614821Y642589D01*
X1615913Y643464D01*
X1617659Y643755D01*
X1618969Y643464D01*
X1620498Y642297D01*
X1621153Y640547D01*
Y632089D01*
G01X1638871D02*
Y643755D01*
G01Y641714D02*
X1637998Y642880D01*
X1636687Y643464D01*
X1635159Y643755D01*
X1633631Y643172D01*
X1632321Y642006D01*
X1631447Y640256D01*
X1631011Y637922D01*
X1631447Y635589D01*
X1632321Y633839D01*
X1633631Y632672D01*
X1635159Y632089D01*
X1636687Y632381D01*
X1637998Y633255D01*
X1638871Y634422D01*
G01X1652441Y649589D02*
Y632089D01*
G01X1649384Y643755D02*
X1655498D01*
G01X1680891Y649589D02*
X1683947Y632089D01*
X1687441Y649589D01*
X1690934Y632089D01*
X1693991Y649589D01*
G01X1702321D02*
X1707561D01*
G01X1704941D02*
Y632089D01*
G01X1702321D02*
X1707561D01*
G01X1717638D02*
Y649589D01*
X1722004D01*
X1723751Y648714D01*
X1725061Y647547D01*
X1726153Y645798D01*
X1727026Y643755D01*
X1727244Y640839D01*
X1727026Y637922D01*
X1726153Y635880D01*
X1725061Y634130D01*
X1723751Y632964D01*
X1722004Y632089D01*
X1717638D01*
G01X1739941Y649589D02*
Y632089D01*
G01X1734919Y649589D02*
X1744963D01*
G01X1752856Y632089D02*
Y649589D01*
G01X1762026D02*
Y632089D01*
G01Y640839D02*
X1752856D01*
G01X1459941Y609105D02*
Y597439D01*
G01Y613772D02*
X1459504Y614064D01*
Y614647D01*
X1459941Y614939D01*
X1460378Y614647D01*
Y614064D01*
X1459941Y613772D01*
G01X1474166Y599480D02*
X1475258Y598314D01*
X1476786Y597439D01*
X1478096D01*
X1479406Y598022D01*
X1480279Y598897D01*
X1480716Y600063D01*
X1480498Y601814D01*
X1479624Y602689D01*
X1475694Y604439D01*
X1474821Y606481D01*
X1475258Y607939D01*
X1476131Y608814D01*
X1477441Y609105D01*
X1478751Y608814D01*
X1480061Y607939D01*
G01X1507419Y597439D02*
Y614939D01*
X1517463Y597439D01*
Y614939D01*
G01X1529941Y597439D02*
X1528194Y597731D01*
X1526666Y598897D01*
X1525356Y600647D01*
X1524482Y602689D01*
X1524046Y605022D01*
Y607356D01*
X1524482Y609689D01*
X1525356Y611731D01*
X1526666Y613480D01*
X1528194Y614647D01*
X1529941Y614939D01*
X1531687Y614647D01*
X1533216Y613480D01*
X1534526Y611731D01*
X1535400Y609689D01*
X1535836Y607356D01*
Y605022D01*
X1535400Y602689D01*
X1534526Y600647D01*
X1533216Y598897D01*
X1531687Y597731D01*
X1529941Y597439D01*
G01X1547441Y614939D02*
Y597439D01*
G01X1542419Y614939D02*
X1552463D01*
G01X1578729Y609105D02*
Y600939D01*
X1579603Y598897D01*
X1580913Y597731D01*
X1582441Y597439D01*
X1583969Y597731D01*
X1585279Y598897D01*
X1586153Y600939D01*
G01Y597439D02*
Y609105D01*
G01X1596666Y599480D02*
X1597758Y598314D01*
X1599286Y597439D01*
X1600596D01*
X1601906Y598022D01*
X1602779Y598897D01*
X1603216Y600063D01*
X1602998Y601814D01*
X1602124Y602689D01*
X1598194Y604439D01*
X1597321Y606481D01*
X1597758Y607939D01*
X1598631Y608814D01*
X1599941Y609105D01*
X1601251Y608814D01*
X1602561Y607939D01*
G01X1614166Y605314D02*
X1621153D01*
X1620498Y607356D01*
X1619406Y608522D01*
X1617878Y609105D01*
X1616349Y608814D01*
X1615039Y607939D01*
X1614166Y605897D01*
X1613729Y604147D01*
Y602397D01*
X1614166Y600647D01*
X1615258Y598897D01*
X1616568Y597731D01*
X1618096Y597439D01*
X1619624Y598022D01*
X1621153Y599772D01*
G01X1638871Y614939D02*
Y597439D01*
G01Y600063D02*
X1637998Y598605D01*
X1636687Y597731D01*
X1635159Y597439D01*
X1633413Y598022D01*
X1632103Y599480D01*
X1631229Y601230D01*
X1631011Y603272D01*
X1631229Y605314D01*
X1632103Y607064D01*
X1633413Y608522D01*
X1635159Y609105D01*
X1636687Y608814D01*
X1637779Y608230D01*
X1638871Y607064D01*
G01X1669941Y609105D02*
Y597439D01*
G01Y613772D02*
X1669504Y614064D01*
Y614647D01*
X1669941Y614939D01*
X1670378Y614647D01*
Y614064D01*
X1669941Y613772D01*
G01X1683729Y597439D02*
Y609105D01*
G01Y606189D02*
X1684603Y607647D01*
X1685913Y608814D01*
X1687659Y609105D01*
X1689187Y608814D01*
X1690498Y607647D01*
X1691153Y605606D01*
Y597439D01*
G01X1722441Y614939D02*
Y597439D01*
G01X1719384Y609105D02*
X1725498D01*
G01X1736229Y597439D02*
Y614939D01*
G01Y606481D02*
X1737321Y607939D01*
X1738413Y608814D01*
X1740159Y609105D01*
X1741469Y608814D01*
X1742998Y607647D01*
X1743653Y605897D01*
Y597439D01*
G01X1757441Y609105D02*
Y597439D01*
G01Y613772D02*
X1757004Y614064D01*
Y614647D01*
X1757441Y614939D01*
X1757878Y614647D01*
Y614064D01*
X1757441Y613772D01*
G01X1771666Y599480D02*
X1772758Y598314D01*
X1774286Y597439D01*
X1775596D01*
X1776906Y598022D01*
X1777779Y598897D01*
X1778216Y600063D01*
X1777998Y601814D01*
X1777124Y602689D01*
X1773194Y604439D01*
X1772321Y606481D01*
X1772758Y607939D01*
X1773631Y608814D01*
X1774941Y609105D01*
X1776251Y608814D01*
X1777561Y607939D01*
G01X1809941Y597439D02*
Y614939D01*
G01X1831371Y597439D02*
Y609105D01*
G01Y607064D02*
X1830498Y608230D01*
X1829187Y608814D01*
X1827659Y609105D01*
X1826131Y608522D01*
X1824821Y607356D01*
X1823947Y605606D01*
X1823511Y603272D01*
X1823947Y600939D01*
X1824821Y599189D01*
X1826131Y598022D01*
X1827659Y597439D01*
X1829187Y597731D01*
X1830498Y598605D01*
X1831371Y599772D01*
G01X1840356Y592189D02*
X1841666Y591606D01*
X1843413Y592189D01*
X1844504Y593355D01*
X1845378Y594814D01*
X1846687Y599480D01*
X1849526Y609105D01*
G01X1842539D02*
X1846687Y599480D01*
G01X1859166Y605314D02*
X1866153D01*
X1865498Y607356D01*
X1864406Y608522D01*
X1862878Y609105D01*
X1861349Y608814D01*
X1860039Y607939D01*
X1859166Y605897D01*
X1858729Y604147D01*
Y602397D01*
X1859166Y600647D01*
X1860258Y598897D01*
X1861568Y597731D01*
X1863096Y597439D01*
X1864624Y598022D01*
X1866153Y599772D01*
G01X1876884Y597439D02*
Y609105D01*
G01Y606772D02*
X1877976Y607939D01*
X1879068Y608814D01*
X1880596Y609105D01*
X1881687Y608814D01*
X1882998Y607939D01*
G01X-20271Y15000D02*
Y676339D01*
G01Y15000D02*
G03X-5271Y0I15000J0D01*
G01Y691339D02*
G03X-20271Y676339I0J-15000D01*
G01X0Y37795D02*
G03X3937Y33858I3937J0D01*
G01X21063Y29921D02*
G03X17126Y33858I-3937J0D01*
G01X3937D02*
X17126D01*
G01X299409Y0D02*
X23031D01*
G01X21063Y1969D02*
X23031Y0D01*
G01X21063Y1969D02*
Y29921D01*
G01X0Y102756D02*
Y37795D01*
G01D02*
G03X-7874I-3937J0D01*
G01X3937Y25984D02*
X13189D01*
G01X-7874Y37795D02*
G03X3937Y25984I11811J0D01*
G01X13189Y0D02*
X-5271D01*
G01X13189Y25984D02*
Y0D01*
G01X3937Y106693D02*
G03X0Y102756I0J-3937D01*
G01X-7874Y68504D02*
G03X0I3937J0D01*
G01X-7874D02*
Y122737D01*
G01X0Y118504D02*
G03X3937Y114567I3937J0D01*
G01Y157382D02*
G03X0Y153445I0J-3937D01*
G01X17126Y157382D02*
G03X21063Y161319I0J3937D01*
G01X0Y118504D02*
Y153445D01*
G01X21063Y219292D02*
Y161319D01*
G01D02*
Y187402D01*
G01X143701Y114567D02*
X3937D01*
G01Y157382D02*
X17126D01*
G01X3937Y106693D02*
X143701D01*
G01X-7874Y153445D02*
Y157382D01*
G01Y153445D02*
G03X0I3937J0D01*
G01Y122737D02*
G03X-7874I-3937J0D01*
G01X-10433Y161070D02*
G03X-7874Y157382I3937J0D01*
G01X-10433Y265210D02*
Y161070D01*
G01X51378Y181496D02*
G03X47441Y177559I0J-3937D01*
G01Y165748D02*
G03X51378Y161811I3937J0D01*
G01X47441Y165748D02*
Y177559D01*
G01X23031Y221260D02*
X21063Y219292D01*
G01X23031Y221260D02*
X63189D01*
G01X0Y272835D02*
G03X3937Y268898I3937J0D01*
G01X21063Y264961D02*
G03X17126Y268898I-3937J0D01*
G01X3937D02*
X17126D01*
G01X299409Y235040D02*
X23031D01*
G01X21063Y237008D02*
X23031Y235040D01*
G01X21063Y237008D02*
Y264961D01*
G01X0Y337796D02*
Y272835D01*
G01D02*
G03X-7874I-3937J0D01*
G01Y268898D02*
G03X-10433Y265210I1378J-3688D01*
G01X-7874Y268898D02*
Y272835D01*
G01X3937Y341733D02*
G03X0Y337796I0J-3937D01*
G01X3937Y341733D02*
X143701D01*
G01X-7874Y303543D02*
Y357781D01*
G01Y303544D02*
G03X0I3937J0D01*
G01X47441Y400788D02*
G03X51378Y396851I3937J0D01*
G01X47441Y400788D02*
Y412599D01*
G01X0Y353544D02*
G03X3937Y349607I3937J0D01*
G01Y392422D02*
G03X0Y388485I0J-3937D01*
G01X17126Y392422D02*
G03X21063Y396359I0J3937D01*
G01X0Y353544D02*
Y388485D01*
G01X21063Y454331D02*
Y396359D01*
G01D02*
Y422441D01*
G01X143701Y349607D02*
X3937D01*
G01Y392422D02*
X17126D01*
G01X-7874Y388480D02*
Y392422D01*
G01Y388485D02*
G03X0I3937J0D01*
G01Y357776D02*
G03X-7874I-3937J0D01*
G01X-10433Y396110D02*
G03X-7874Y392422I3937J0D01*
G01X-10433Y500250D02*
Y396110D01*
G01X51378Y416536D02*
G03X47441Y412599I0J-3937D01*
G01X23031Y456300D02*
X21063Y454331D01*
G01X23031Y456300D02*
X63189D01*
G01X0Y507874D02*
G03X3937Y503937I3937J0D01*
G01X21063Y500000D02*
G03X17126Y503937I-3937J0D01*
G01X3937D02*
X17126D01*
G01X299409Y470079D02*
X23031D01*
G01X21063Y472048D02*
X23031Y470079D01*
G01X21063Y472048D02*
Y500000D01*
G01X0Y572835D02*
Y507874D01*
G01D02*
G03X-7874I-3937J0D01*
G01Y503937D02*
Y507880D01*
G01Y503937D02*
G03X-10433Y500250I1378J-3688D01*
G01X3937Y576772D02*
G03X0Y572835I0J-3937D01*
G01X3937Y576772D02*
X143701D01*
G01X0Y588583D02*
G03X3937Y584646I3937J0D01*
G01X0Y588583D02*
Y623524D01*
G01X143701Y584646D02*
X3937D01*
G01X-7874Y538578D02*
Y592823D01*
G01Y538583D02*
G03X0I3937J0D01*
G01X51378Y651576D02*
G03X47441Y647639I0J-3937D01*
G01Y635828D02*
G03X51378Y631891I3937J0D01*
G01X47441Y635828D02*
Y647639D01*
G01X3937Y627461D02*
G03X0Y623524I0J-3937D01*
G01X17126Y627461D02*
G03X21063Y631398I0J3937D01*
G01Y689371D02*
Y631398D01*
G01D02*
Y657481D01*
G01X3937Y627461D02*
X17126D01*
G01X1830Y651994D02*
G03I-4292J0D01*
G01X-7874Y623517D02*
Y623536D01*
G01X13189Y691339D02*
Y635335D01*
G01X3937D02*
X13189D01*
G01X3937D02*
G03X-7874Y623524I0J-11811D01*
G01D02*
G03X0I3937J0D01*
G01Y592816D02*
G03X-7874I-3937J0D01*
G01X23031Y691339D02*
X21063Y689371D01*
G01X23031Y691339D02*
X63189D01*
G01X13189D02*
X-5271D01*
G01X63189Y161811D02*
G03X67126Y165748I0J3937D01*
G01X73425D02*
G03X77362Y161811I3937J0D01*
G01X89173D02*
G03X93110Y165748I0J3937D01*
G01X99409D02*
G03X103346Y161811I3937J0D01*
G01X63189D02*
X51378D01*
G01X89173D02*
X77362D01*
G01X115157D02*
X103346D01*
G01X89173Y114567D02*
G03Y106693I0J-3937D01*
G01X58465D02*
G03Y114567I0J3937D01*
G01X67126Y177559D02*
G03X63189Y181496I-3937J0D01*
G01X77362D02*
G03X73425Y177559I0J-3937D01*
G01X93110D02*
G03X89173Y181496I-3937J0D01*
G01X103346D02*
G03X99409Y177559I0J-3937D01*
G01X67126D02*
Y165748D01*
G01X73425D02*
Y177559D01*
G01X93110D02*
Y165748D01*
G01X99409D02*
Y177559D01*
G01X103346Y181496D02*
X115157D01*
G01X77362D02*
X89173D01*
G01X51378D02*
X63189D01*
G01X65157Y191930D02*
G03X72638I3740J0D01*
G01X65157Y219292D02*
Y191930D01*
G01X74606Y221260D02*
X72638Y219292D01*
G01D02*
Y191930D01*
G01X65157Y219292D02*
X63189Y221260D01*
G01X74606D02*
X350984D01*
G01X89173Y349607D02*
G03Y341733I0J-3937D01*
G01X58465D02*
G03Y349607I0J3937D01*
G01X63189Y396851D02*
G03X67126Y400788I0J3937D01*
G01X73425D02*
G03X77362Y396851I3937J0D01*
G01X89173D02*
G03X93110Y400788I0J3937D01*
G01X99409D02*
G03X103346Y396851I3937J0D01*
G01X67126Y412599D02*
Y400788D01*
G01X73425D02*
Y412599D01*
G01X93110D02*
Y400788D01*
G01X99409D02*
Y412599D01*
G01X63189Y396851D02*
X51378D01*
G01X89173D02*
X77362D01*
G01X115157D02*
X103346D01*
G01X67126Y412599D02*
G03X63189Y416536I-3937J0D01*
G01X77362D02*
G03X73425Y412599I0J-3937D01*
G01X93110D02*
G03X89173Y416536I-3937J0D01*
G01X103346D02*
G03X99409Y412599I0J-3937D01*
G01X103346Y416536D02*
X115157D01*
G01X77362D02*
X89173D01*
G01X51378D02*
X63189D01*
G01X65157Y426969D02*
G03X72638I3740J0D01*
G01X65157Y454331D02*
Y426969D01*
G01X74606Y456300D02*
X72638Y454331D01*
G01D02*
Y426969D01*
G01X65157Y454331D02*
X63189Y456300D01*
G01X74606D02*
X350984D01*
G01X89173Y584646D02*
G03Y576772I0J-3937D01*
G01X58465D02*
G03Y584646I0J3937D01*
G01X67126Y647639D02*
G03X63189Y651576I-3937J0D01*
G01Y631891D02*
G03X67126Y635828I0J3937D01*
G01X73425D02*
G03X77362Y631891I3937J0D01*
G01Y651576D02*
G03X73425Y647639I0J-3937D01*
G01X93110D02*
G03X89173Y651576I-3937J0D01*
G01Y631891D02*
G03X93110Y635828I0J3937D01*
G01X103346Y651576D02*
G03X99409Y647639I0J-3937D01*
G01Y635828D02*
G03X103346Y631891I3937J0D01*
G01X67126Y647639D02*
Y635828D01*
G01X73425D02*
Y647639D01*
G01X93110D02*
Y635828D01*
G01X99409D02*
Y647639D01*
G01X63189Y631891D02*
X51378D01*
G01X89173D02*
X77362D01*
G01X115157D02*
X103346D01*
G01Y651576D02*
X115157D01*
G01X77362D02*
X89173D01*
G01X51378D02*
X63189D01*
G01X65157Y662009D02*
G03X72638I3740J0D01*
G01X65157Y689371D02*
Y662009D01*
G01X74606Y691339D02*
X72638Y689371D01*
G01D02*
Y662009D01*
G01X65157Y689371D02*
X63189Y691339D01*
G01X74606D02*
X350984D01*
G01X147638Y102756D02*
G03X151575Y98819I3937J0D01*
G01X147638Y102756D02*
G03X143701Y106693I-3937J0D01*
G01X147638Y102756D02*
G03X151575Y98819I3937J0D01*
G01X147638Y102756D02*
G03X143701Y106693I-3937J0D01*
G01X147638Y102756D02*
G03X151575Y98819I3937J0D01*
G01X147638Y102756D02*
G03X143701Y106693I-3937J0D01*
G01X151575Y98819D02*
X222441D01*
G01X115157Y161811D02*
G03X119094Y165748I0J3937D01*
G01X151575Y122441D02*
G03X147638Y118504I0J-3937D01*
G01X143701Y114567D02*
G03X147638Y118504I0J3937D01*
G01X143701Y114567D02*
X112205D01*
G01X143701D02*
G03X147638Y118504I0J3937D01*
G01X151575Y122441D02*
G03X147638Y118504I0J-3937D01*
G01X151575Y122441D02*
G03X147638Y118504I0J-3937D01*
G01X143701Y114567D02*
G03X147638Y118504I0J3937D01*
G01X222441Y122441D02*
X151575D01*
G01X143701Y106693D02*
X112205D01*
G01X119094Y177559D02*
G03X115157Y181496I-3937J0D01*
G01X119094Y177559D02*
Y165748D01*
G01X147638Y337796D02*
G03X151575Y333859I3937J0D01*
G01X147638Y337796D02*
G03X143701Y341733I-3937J0D01*
G01D02*
X112205D01*
G01X147638Y337796D02*
G03X151575Y333859I3937J0D01*
G01X147638Y337796D02*
G03X143701Y341733I-3937J0D01*
G01X147638Y337796D02*
G03X151575Y333859I3937J0D01*
G01X147638Y337796D02*
G03X143701Y341733I-3937J0D01*
G01X151575Y333859D02*
X222441D01*
G01X115157Y396851D02*
G03X119094Y400788I0J3937D01*
G01Y412599D02*
Y400788D01*
G01X151575Y357481D02*
G03X147638Y353544I0J-3937D01*
G01X143701Y349607D02*
G03X147638Y353544I0J3937D01*
G01X143701Y349607D02*
X112205D01*
G01X143701D02*
G03X147638Y353544I0J3937D01*
G01X151575Y357481D02*
G03X147638Y353544I0J-3937D01*
G01X151575Y357481D02*
G03X147638Y353544I0J-3937D01*
G01X143701Y349607D02*
G03X147638Y353544I0J3937D01*
G01X222441Y357481D02*
X151575D01*
G01X119094Y412599D02*
G03X115157Y416536I-3937J0D01*
G01X147638Y572835D02*
G03X151575Y568898I3937J0D01*
G01X147638Y572835D02*
G03X143701Y576772I-3937J0D01*
G01D02*
X112205D01*
G01X147638Y572835D02*
G03X151575Y568898I3937J0D01*
G01X147638Y572835D02*
G03X143701Y576772I-3937J0D01*
G01X147638Y572835D02*
G03X151575Y568898I3937J0D01*
G01X147638Y572835D02*
G03X143701Y576772I-3937J0D01*
G01X151575Y568898D02*
X222441D01*
G01X151575Y592520D02*
G03X147638Y588583I0J-3937D01*
G01X143701Y584646D02*
G03X147638Y588583I0J3937D01*
G01X143701Y584646D02*
X112205D01*
G01X143701D02*
G03X147638Y588583I0J3937D01*
G01X151575Y592520D02*
G03X147638Y588583I0J-3937D01*
G01X151575Y592520D02*
G03X147638Y588583I0J-3937D01*
G01X143701Y584646D02*
G03X147638Y588583I0J3937D01*
G01X119094Y647639D02*
G03X115157Y651576I-3937J0D01*
G01Y631891D02*
G03X119094Y635828I0J3937D01*
G01Y647639D02*
Y635828D01*
G01X222441Y592520D02*
X151575D01*
G01X222441Y98819D02*
G03X226378Y102756I0J3937D01*
G01X230315Y106693D02*
G03X226378Y102756I0J-3937D01*
G01X230315Y106693D02*
G03X226378Y102756I0J-3937D01*
G01X222441Y98819D02*
G03X226378Y102756I0J3937D01*
G01X222441Y98819D02*
G03X226378Y102756I0J3937D01*
G01X230315Y106693D02*
G03X226378Y102756I0J-3937D01*
G01Y118504D02*
G03X222441Y122441I-3937J0D01*
G01X226378Y118504D02*
G03X230315Y114567I3937J0D01*
G01D02*
X261811D01*
G01X226378Y118504D02*
G03X222441Y122441I-3937J0D01*
G01X226378Y118504D02*
G03X230315Y114567I3937J0D01*
G01X226378Y118504D02*
G03X222441Y122441I-3937J0D01*
G01X226378Y118504D02*
G03X230315Y114567I3937J0D01*
G01X370079D02*
X230315D01*
G01Y106693D02*
X261811D01*
G01X230315D02*
X370079D01*
G01X222441Y333859D02*
G03X226378Y337796I0J3937D01*
G01X230315Y341733D02*
G03X226378Y337796I0J-3937D01*
G01X230315Y341733D02*
X261811D01*
G01X230315D02*
G03X226378Y337796I0J-3937D01*
G01X222441Y333859D02*
G03X226378Y337796I0J3937D01*
G01X222441Y333859D02*
G03X226378Y337796I0J3937D01*
G01X230315Y341733D02*
G03X226378Y337796I0J-3937D01*
G01X230315Y341733D02*
X370079D01*
G01X226378Y353544D02*
G03X222441Y357481I-3937J0D01*
G01X226378Y353544D02*
G03X230315Y349607I3937J0D01*
G01D02*
X261811D01*
G01X226378Y353544D02*
G03X222441Y357481I-3937J0D01*
G01X226378Y353544D02*
G03X230315Y349607I3937J0D01*
G01X226378Y353544D02*
G03X222441Y357481I-3937J0D01*
G01X226378Y353544D02*
G03X230315Y349607I3937J0D01*
G01X370079D02*
X230315D01*
G01X222441Y568898D02*
G03X226378Y572835I0J3937D01*
G01X230315Y576772D02*
G03X226378Y572835I0J-3937D01*
G01X230315Y576772D02*
X261811D01*
G01X230315D02*
G03X226378Y572835I0J-3937D01*
G01X222441Y568898D02*
G03X226378Y572835I0J3937D01*
G01X222441Y568898D02*
G03X226378Y572835I0J3937D01*
G01X230315Y576772D02*
G03X226378Y572835I0J-3937D01*
G01X230315Y576772D02*
X370079D01*
G01X226378Y588583D02*
G03X222441Y592520I-3937J0D01*
G01X226378Y588583D02*
G03X230315Y584646I3937J0D01*
G01D02*
X261811D01*
G01X226378Y588583D02*
G03X222441Y592520I-3937J0D01*
G01X226378Y588583D02*
G03X230315Y584646I3937J0D01*
G01X226378Y588583D02*
G03X222441Y592520I-3937J0D01*
G01X226378Y588583D02*
G03X230315Y584646I3937J0D01*
G01X370079D02*
X230315D01*
G01X280906Y43701D02*
G03X284843Y39764I3937J0D01*
G01X270669D02*
G03X274606Y43701I0J3937D01*
G01X254921D02*
G03X258858Y39764I3937J0D01*
G01X270669D02*
X258858D01*
G01X296654D02*
X284843D01*
G01Y59449D02*
G03X280906Y55512I0J-3937D01*
G01X258858Y59449D02*
G03X254921Y55512I0J-3937D01*
G01X274606D02*
G03X270669Y59449I-3937J0D01*
G01X280906Y43701D02*
Y55512D01*
G01X274606D02*
Y43701D01*
G01X254921D02*
Y55512D01*
G01X284843Y59449D02*
X296654D01*
G01X258858D02*
X270669D01*
G01X284843Y106693D02*
G03Y114567I0J3937D01*
G01X280906Y278741D02*
G03X284843Y274804I3937J0D01*
G01X270669D02*
G03X274606Y278741I0J3937D01*
G01X254921D02*
G03X258858Y274804I3937J0D01*
G01X280906Y278741D02*
Y290552D01*
G01X274606D02*
Y278741D01*
G01X254921D02*
Y290552D01*
G01X270669Y274804D02*
X258858D01*
G01X296654D02*
X284843D01*
G01Y294489D02*
G03X280906Y290552I0J-3937D01*
G01X258858Y294489D02*
G03X254921Y290552I0J-3937D01*
G01X274606D02*
G03X270669Y294489I-3937J0D01*
G01X284843D02*
X296654D01*
G01X258858D02*
X270669D01*
G01X284843Y341733D02*
G03Y349607I0J3937D01*
G01X280906Y513780D02*
G03X284843Y509843I3937J0D01*
G01Y529528D02*
G03X280906Y525591I0J-3937D01*
G01X270669Y509843D02*
G03X274606Y513780I0J3937D01*
G01X254921D02*
G03X258858Y509843I3937J0D01*
G01Y529528D02*
G03X254921Y525591I0J-3937D01*
G01X274606D02*
G03X270669Y529528I-3937J0D01*
G01X280906Y513780D02*
Y525591D01*
G01X274606D02*
Y513780D01*
G01X254921D02*
Y525591D01*
G01X284843Y529528D02*
X296654D01*
G01X258858D02*
X270669D01*
G01Y509843D02*
X258858D01*
G01X296654D02*
X284843D01*
G01Y576772D02*
G03Y584646I0J3937D01*
G01X322638Y39764D02*
G03X326575Y43701I0J3937D01*
G01X306890D02*
G03X310827Y39764I3937J0D01*
G01X296654D02*
G03X300591Y43701I0J3937D01*
G01X322638Y39764D02*
X310827D01*
G01X308858Y29331D02*
G03X301378I-3740J0D01*
G01X350984Y0D02*
X352953Y1969D01*
G01X308858D02*
Y29331D01*
G01X299409Y0D02*
X301378Y1969D01*
G01D02*
Y29331D01*
G01X308858Y1969D02*
X310827Y0D01*
G01X350984D02*
X310827D01*
G01Y59449D02*
G03X306890Y55512I0J-3937D01*
G01X326575D02*
G03X322638Y59449I-3937J0D01*
G01X300591Y55512D02*
G03X296654Y59449I-3937J0D01*
G01X326575Y55512D02*
Y43701D01*
G01X306890D02*
Y55512D01*
G01X300591D02*
Y43701D01*
G01X310827Y59449D02*
X322638D01*
G01X315551Y114567D02*
G03Y106693I0J-3937D01*
G01X352953Y219292D02*
X350984Y221260D01*
G01X322638Y274804D02*
G03X326575Y278741I0J3937D01*
G01X306890D02*
G03X310827Y274804I3937J0D01*
G01X296654D02*
G03X300591Y278741I0J3937D01*
G01X326575Y290552D02*
Y278741D01*
G01X306890D02*
Y290552D01*
G01X300591D02*
Y278741D01*
G01X322638Y274804D02*
X310827D01*
G01X308858Y264370D02*
G03X301378I-3740J0D01*
G01X350984Y235040D02*
X352953Y237008D01*
G01X308858D02*
Y264370D01*
G01X299409Y235040D02*
X301378Y237008D01*
G01D02*
Y264370D01*
G01X308858Y237008D02*
X310827Y235040D01*
G01X350984D02*
X310827D01*
G01Y294489D02*
G03X306890Y290552I0J-3937D01*
G01X326575D02*
G03X322638Y294489I-3937J0D01*
G01X300591Y290552D02*
G03X296654Y294489I-3937J0D01*
G01X310827D02*
X322638D01*
G01X315551Y349607D02*
G03Y341733I0J-3937D01*
G01X352953Y454331D02*
X350984Y456300D01*
G01X322638Y509843D02*
G03X326575Y513780I0J3937D01*
G01X306890D02*
G03X310827Y509843I3937J0D01*
G01Y529528D02*
G03X306890Y525591I0J-3937D01*
G01X326575D02*
G03X322638Y529528I-3937J0D01*
G01X300591Y525591D02*
G03X296654Y529528I-3937J0D01*
G01Y509843D02*
G03X300591Y513780I0J3937D01*
G01X326575Y525591D02*
Y513780D01*
G01X306890D02*
Y525591D01*
G01X300591D02*
Y513780D01*
G01X310827Y529528D02*
X322638D01*
G01Y509843D02*
X310827D01*
G01X308858Y499410D02*
G03X301378I-3740J0D01*
G01X350984Y470079D02*
X352953Y472048D01*
G01X308858D02*
Y499410D01*
G01X299409Y470079D02*
X301378Y472048D01*
G01D02*
Y499410D01*
G01X308858Y472048D02*
X310827Y470079D01*
G01X350984D02*
X310827D01*
G01X315551Y584646D02*
G03Y576772I0J-3937D01*
G01X352953Y689371D02*
X350984Y691339D01*
G01X381890Y37795D02*
G03X385827Y33858I3937J0D01*
G01X402953Y29921D02*
G03X399016Y33858I-3937J0D01*
G01X385827D02*
X399016D01*
G01X681299Y0D02*
X404921D01*
G01X402953Y1969D02*
X404921Y0D01*
G01X402953Y1969D02*
Y29921D01*
G01X381890Y102756D02*
Y37795D01*
G01X352953Y1969D02*
Y59941D01*
G01D02*
Y33858D01*
G01X385827Y106693D02*
G03X381890Y102756I0J-3937D01*
G01X374016D02*
G03X370079Y106693I-3937J0D01*
G01Y63878D02*
G03X374016Y67815I0J3937D01*
G01X356890Y63878D02*
G03X352953Y59941I0J-3937D01*
G01X374016Y102756D02*
Y67815D01*
G01X370079Y63878D02*
X356890D01*
G01X374016Y98524D02*
G03X381890I3937J0D01*
G01Y67815D02*
G03X374016I-3937J0D01*
G01X385827Y106693D02*
X525591D01*
G01X370079Y114567D02*
G03X374016Y118504I0J3937D01*
G01D02*
Y183465D01*
G01X381890Y118504D02*
G03X385827Y114567I3937J0D01*
G01Y157382D02*
G03X381890Y153445I0J-3937D01*
G01X399016Y157382D02*
G03X402953Y161319I0J3937D01*
G01X381890Y118504D02*
Y153445D01*
G01X402953Y219292D02*
Y161319D01*
G01D02*
Y187402D01*
G01X525591Y114567D02*
X385827D01*
G01Y157382D02*
X399016D01*
G01X374016Y153445D02*
G03X381890I3937J0D01*
G01Y122737D02*
G03X374016I-3937J0D01*
G01Y183465D02*
G03X370079Y187402I-3937J0D01*
G01X352953Y191339D02*
G03X356890Y187402I3937J0D01*
G01X370079D02*
X356890D01*
G01X352953Y219292D02*
Y191339D01*
G01X404921Y221260D02*
X402953Y219292D01*
G01X404921Y221260D02*
X445079D01*
G01X352953Y237008D02*
Y294981D01*
G01D02*
Y268898D01*
G01X381890Y272835D02*
G03X385827Y268898I3937J0D01*
G01X402953Y264961D02*
G03X399016Y268898I-3937J0D01*
G01X385827D02*
X399016D01*
G01X681299Y235040D02*
X404921D01*
G01X402953Y237008D02*
X404921Y235040D01*
G01X402953Y237008D02*
Y264961D01*
G01X381890Y337796D02*
Y272835D01*
G01X374016Y337796D02*
G03X370079Y341733I-3937J0D01*
G01Y298918D02*
G03X374016Y302855I0J3937D01*
G01X356890Y298918D02*
G03X352953Y294981I0J-3937D01*
G01X374016Y337796D02*
Y302855D01*
G01X370079Y298918D02*
X356890D01*
G01X385827Y341733D02*
G03X381890Y337796I0J-3937D01*
G01X385827Y341733D02*
X525591D01*
G01X374016Y333563D02*
G03X381890I3937J0D01*
G01Y302855D02*
G03X374016I-3937J0D01*
G01X381890Y353544D02*
G03X385827Y349607I3937J0D01*
G01Y392422D02*
G03X381890Y388485I0J-3937D01*
G01X399016Y392422D02*
G03X402953Y396359I0J3937D01*
G01X381890Y353544D02*
Y388485D01*
G01X402953Y454331D02*
Y396359D01*
G01D02*
Y422441D01*
G01X525591Y349607D02*
X385827D01*
G01Y392422D02*
X399016D01*
G01X370079Y349607D02*
G03X374016Y353544I0J3937D01*
G01D02*
Y418504D01*
G01Y388485D02*
G03X381890I3937J0D01*
G01Y357776D02*
G03X374016I-3937J0D01*
G01X404921Y456300D02*
X402953Y454331D01*
G01X404921Y456300D02*
X445079D01*
G01X374016Y418504D02*
G03X370079Y422441I-3937J0D01*
G01X352953Y426378D02*
G03X356890Y422441I3937J0D01*
G01X370079D02*
X356890D01*
G01X352953Y454331D02*
Y426378D01*
G01Y472048D02*
Y530020D01*
G01D02*
Y503937D01*
G01X381890Y507874D02*
G03X385827Y503937I3937J0D01*
G01X402953Y500000D02*
G03X399016Y503937I-3937J0D01*
G01X385827D02*
X399016D01*
G01X681299Y470079D02*
X404921D01*
G01X402953Y472048D02*
X404921Y470079D01*
G01X402953Y472048D02*
Y500000D01*
G01X381890Y572835D02*
Y507874D01*
G01X374016Y572835D02*
G03X370079Y576772I-3937J0D01*
G01Y533957D02*
G03X374016Y537894I0J3937D01*
G01X356890Y533957D02*
G03X352953Y530020I0J-3937D01*
G01X374016Y572835D02*
Y537894D01*
G01X370079Y533957D02*
X356890D01*
G01X385827Y576772D02*
G03X381890Y572835I0J-3937D01*
G01X385827Y576772D02*
X525591D01*
G01X381890Y588583D02*
G03X385827Y584646I3937J0D01*
G01X381890Y588583D02*
Y623524D01*
G01X525591Y584646D02*
X385827D01*
G01X370079D02*
G03X374016Y588583I0J3937D01*
G01D02*
Y653544D01*
G01Y568603D02*
G03X381890I3937J0D01*
G01Y537894D02*
G03X374016I-3937J0D01*
G01X385827Y627461D02*
G03X381890Y623524I0J-3937D01*
G01X399016Y627461D02*
G03X402953Y631398I0J3937D01*
G01Y689371D02*
Y631398D01*
G01D02*
Y657481D01*
G01X385827Y627461D02*
X399016D01*
G01X374016Y623524D02*
G03X381890I3937J0D01*
G01Y592816D02*
G03X374016I-3937J0D01*
G01X404921Y691339D02*
X402953Y689371D01*
G01X404921Y691339D02*
X445079D01*
G01X374016Y653544D02*
G03X370079Y657481I-3937J0D01*
G01X352953Y661418D02*
G03X356890Y657481I3937J0D01*
G01X370079D02*
X356890D01*
G01X352953Y689371D02*
Y661418D01*
G01X445079Y161811D02*
G03X449016Y165748I0J3937D01*
G01X429331D02*
G03X433268Y161811I3937J0D01*
G01X455315Y165748D02*
G03X459252Y161811I3937J0D01*
G01X471063D02*
G03X475000Y165748I0J3937D01*
G01X445079Y161811D02*
X433268D01*
G01X471063D02*
X459252D01*
G01X471063Y114567D02*
G03Y106693I0J-3937D01*
G01X440354D02*
G03Y114567I0J3937D01*
G01X433268Y181496D02*
G03X429331Y177559I0J-3937D01*
G01X449016D02*
G03X445079Y181496I-3937J0D01*
G01X459252D02*
G03X455315Y177559I0J-3937D01*
G01X475000D02*
G03X471063Y181496I-3937J0D01*
G01X429331Y165748D02*
Y177559D01*
G01X449016D02*
Y165748D01*
G01X455315D02*
Y177559D01*
G01X459252Y181496D02*
X471063D01*
G01X433268D02*
X445079D01*
G01X447047Y191930D02*
G03X454528I3740J0D01*
G01X447047Y219292D02*
Y191930D01*
G01X456496Y221260D02*
X454528Y219292D01*
G01D02*
Y191930D01*
G01X447047Y219292D02*
X445079Y221260D01*
G01X456496D02*
X732874D01*
G01X471063Y349607D02*
G03Y341733I0J-3937D01*
G01X440354D02*
G03Y349607I0J3937D01*
G01X445079Y396851D02*
G03X449016Y400788I0J3937D01*
G01X429331D02*
G03X433268Y396851I3937J0D01*
G01X455315Y400788D02*
G03X459252Y396851I3937J0D01*
G01X471063D02*
G03X475000Y400788I0J3937D01*
G01X429331D02*
Y412599D01*
G01X449016D02*
Y400788D01*
G01X455315D02*
Y412599D01*
G01X445079Y396851D02*
X433268D01*
G01X471063D02*
X459252D01*
G01X433268Y416536D02*
G03X429331Y412599I0J-3937D01*
G01X449016D02*
G03X445079Y416536I-3937J0D01*
G01X459252D02*
G03X455315Y412599I0J-3937D01*
G01X475000D02*
G03X471063Y416536I-3937J0D01*
G01X459252D02*
X471063D01*
G01X433268D02*
X445079D01*
G01X447047Y426969D02*
G03X454528I3740J0D01*
G01X447047Y454331D02*
Y426969D01*
G01X456496Y456300D02*
X454528Y454331D01*
G01D02*
Y426969D01*
G01X447047Y454331D02*
X445079Y456300D01*
G01X456496D02*
X732874D01*
G01X471063Y584646D02*
G03Y576772I0J-3937D01*
G01X440354D02*
G03Y584646I0J3937D01*
G01X433268Y651576D02*
G03X429331Y647639I0J-3937D01*
G01X449016D02*
G03X445079Y651576I-3937J0D01*
G01Y631891D02*
G03X449016Y635828I0J3937D01*
G01X429331D02*
G03X433268Y631891I3937J0D01*
G01X455315Y635828D02*
G03X459252Y631891I3937J0D01*
G01Y651576D02*
G03X455315Y647639I0J-3937D01*
G01X475000D02*
G03X471063Y651576I-3937J0D01*
G01Y631891D02*
G03X475000Y635828I0J3937D01*
G01X429331D02*
Y647639D01*
G01X449016D02*
Y635828D01*
G01X455315D02*
Y647639D01*
G01X445079Y631891D02*
X433268D01*
G01X471063D02*
X459252D01*
G01Y651576D02*
X471063D01*
G01X433268D02*
X445079D01*
G01X447047Y662009D02*
G03X454528I3740J0D01*
G01X447047Y689371D02*
Y662009D01*
G01X456496Y691339D02*
X454528Y689371D01*
G01D02*
Y662009D01*
G01X447047Y689371D02*
X445079Y691339D01*
G01X456496D02*
X732874D01*
G01X529528Y102756D02*
G03X533465Y98819I3937J0D01*
G01X529528Y102756D02*
G03X525591Y106693I-3937J0D01*
G01X529528Y102756D02*
G03X533465Y98819I3937J0D01*
G01X529528Y102756D02*
G03X525591Y106693I-3937J0D01*
G01X529528Y102756D02*
G03X533465Y98819I3937J0D01*
G01X529528Y102756D02*
G03X525591Y106693I-3937J0D01*
G01X533465Y98819D02*
X604331D01*
G01X525591Y106693D02*
X494094D01*
G01X497047Y161811D02*
G03X500984Y165748I0J3937D01*
G01X481299D02*
G03X485236Y161811I3937J0D01*
G01X497047D02*
X485236D01*
G01X533465Y122441D02*
G03X529528Y118504I0J-3937D01*
G01X525591Y114567D02*
G03X529528Y118504I0J3937D01*
G01X525591Y114567D02*
X494094D01*
G01X525591D02*
G03X529528Y118504I0J3937D01*
G01X533465Y122441D02*
G03X529528Y118504I0J-3937D01*
G01X533465Y122441D02*
G03X529528Y118504I0J-3937D01*
G01X525591Y114567D02*
G03X529528Y118504I0J3937D01*
G01X604331Y122441D02*
X533465D01*
G01X485236Y181496D02*
G03X481299Y177559I0J-3937D01*
G01X500984D02*
G03X497047Y181496I-3937J0D01*
G01X475000Y177559D02*
Y165748D01*
G01X481299D02*
Y177559D01*
G01X500984D02*
Y165748D01*
G01X485236Y181496D02*
X497047D01*
G01X529528Y337796D02*
G03X533465Y333859I3937J0D01*
G01X529528Y337796D02*
G03X525591Y341733I-3937J0D01*
G01D02*
X494094D01*
G01X529528Y337796D02*
G03X533465Y333859I3937J0D01*
G01X529528Y337796D02*
G03X525591Y341733I-3937J0D01*
G01X529528Y337796D02*
G03X533465Y333859I3937J0D01*
G01X529528Y337796D02*
G03X525591Y341733I-3937J0D01*
G01X533465Y333859D02*
X604331D01*
G01X497047Y396851D02*
G03X500984Y400788I0J3937D01*
G01X481299D02*
G03X485236Y396851I3937J0D01*
G01X475000Y412599D02*
Y400788D01*
G01X481299D02*
Y412599D01*
G01X500984D02*
Y400788D01*
G01X497047Y396851D02*
X485236D01*
G01X533465Y357481D02*
G03X529528Y353544I0J-3937D01*
G01X525591Y349607D02*
G03X529528Y353544I0J3937D01*
G01X525591Y349607D02*
X494094D01*
G01X525591D02*
G03X529528Y353544I0J3937D01*
G01X533465Y357481D02*
G03X529528Y353544I0J-3937D01*
G01X533465Y357481D02*
G03X529528Y353544I0J-3937D01*
G01X525591Y349607D02*
G03X529528Y353544I0J3937D01*
G01X604331Y357481D02*
X533465D01*
G01X485236Y416536D02*
G03X481299Y412599I0J-3937D01*
G01X500984D02*
G03X497047Y416536I-3937J0D01*
G01X485236D02*
X497047D01*
G01X529528Y572835D02*
G03X533465Y568898I3937J0D01*
G01X529528Y572835D02*
G03X525591Y576772I-3937J0D01*
G01D02*
X494094D01*
G01X529528Y572835D02*
G03X533465Y568898I3937J0D01*
G01X529528Y572835D02*
G03X525591Y576772I-3937J0D01*
G01X529528Y572835D02*
G03X533465Y568898I3937J0D01*
G01X529528Y572835D02*
G03X525591Y576772I-3937J0D01*
G01X533465Y568898D02*
X604331D01*
G01X533465Y592520D02*
G03X529528Y588583I0J-3937D01*
G01X525591Y584646D02*
G03X529528Y588583I0J3937D01*
G01X525591Y584646D02*
X494094D01*
G01X525591D02*
G03X529528Y588583I0J3937D01*
G01X533465Y592520D02*
G03X529528Y588583I0J-3937D01*
G01X533465Y592520D02*
G03X529528Y588583I0J-3937D01*
G01X525591Y584646D02*
G03X529528Y588583I0J3937D01*
G01X485236Y651576D02*
G03X481299Y647639I0J-3937D01*
G01X500984D02*
G03X497047Y651576I-3937J0D01*
G01Y631891D02*
G03X500984Y635828I0J3937D01*
G01X481299D02*
G03X485236Y631891I3937J0D01*
G01X475000Y647639D02*
Y635828D01*
G01X481299D02*
Y647639D01*
G01X500984D02*
Y635828D01*
G01X497047Y631891D02*
X485236D01*
G01Y651576D02*
X497047D01*
G01X604331Y592520D02*
X533465D01*
G01X652559Y39764D02*
G03X656496Y43701I0J3937D01*
G01X636811D02*
G03X640748Y39764I3937J0D01*
G01X652559D02*
X640748D01*
G01Y59449D02*
G03X636811Y55512I0J-3937D01*
G01X656496D02*
G03X652559Y59449I-3937J0D01*
G01X656496Y55512D02*
Y43701D01*
G01X636811D02*
Y55512D01*
G01X640748Y59449D02*
X652559D01*
G01X604331Y98819D02*
G03X608268Y102756I0J3937D01*
G01X612205Y106693D02*
G03X608268Y102756I0J-3937D01*
G01X612205Y106693D02*
G03X608268Y102756I0J-3937D01*
G01X604331Y98819D02*
G03X608268Y102756I0J3937D01*
G01X604331Y98819D02*
G03X608268Y102756I0J3937D01*
G01X612205Y106693D02*
G03X608268Y102756I0J-3937D01*
G01X612205Y106693D02*
X643701D01*
G01X612205D02*
X751969D01*
G01X608268Y118504D02*
G03X604331Y122441I-3937J0D01*
G01X608268Y118504D02*
G03X612205Y114567I3937J0D01*
G01D02*
X643701D01*
G01X608268Y118504D02*
G03X604331Y122441I-3937J0D01*
G01X608268Y118504D02*
G03X612205Y114567I3937J0D01*
G01X608268Y118504D02*
G03X604331Y122441I-3937J0D01*
G01X608268Y118504D02*
G03X612205Y114567I3937J0D01*
G01X751969D02*
X612205D01*
G01X652559Y274804D02*
G03X656496Y278741I0J3937D01*
G01X636811D02*
G03X640748Y274804I3937J0D01*
G01X656496Y290552D02*
Y278741D01*
G01X636811D02*
Y290552D01*
G01X652559Y274804D02*
X640748D01*
G01Y294489D02*
G03X636811Y290552I0J-3937D01*
G01X656496D02*
G03X652559Y294489I-3937J0D01*
G01X640748D02*
X652559D01*
G01X604331Y333859D02*
G03X608268Y337796I0J3937D01*
G01X612205Y341733D02*
G03X608268Y337796I0J-3937D01*
G01X612205Y341733D02*
X643701D01*
G01X612205D02*
G03X608268Y337796I0J-3937D01*
G01X604331Y333859D02*
G03X608268Y337796I0J3937D01*
G01X604331Y333859D02*
G03X608268Y337796I0J3937D01*
G01X612205Y341733D02*
G03X608268Y337796I0J-3937D01*
G01X612205Y341733D02*
X751969D01*
G01X608268Y353544D02*
G03X604331Y357481I-3937J0D01*
G01X608268Y353544D02*
G03X612205Y349607I3937J0D01*
G01D02*
X643701D01*
G01X608268Y353544D02*
G03X604331Y357481I-3937J0D01*
G01X608268Y353544D02*
G03X612205Y349607I3937J0D01*
G01X608268Y353544D02*
G03X604331Y357481I-3937J0D01*
G01X608268Y353544D02*
G03X612205Y349607I3937J0D01*
G01X751969D02*
X612205D01*
G01X652559Y509843D02*
G03X656496Y513780I0J3937D01*
G01X636811D02*
G03X640748Y509843I3937J0D01*
G01Y529528D02*
G03X636811Y525591I0J-3937D01*
G01X656496D02*
G03X652559Y529528I-3937J0D01*
G01X656496Y525591D02*
Y513780D01*
G01X636811D02*
Y525591D01*
G01X640748Y529528D02*
X652559D01*
G01Y509843D02*
X640748D01*
G01X604331Y568898D02*
G03X608268Y572835I0J3937D01*
G01X612205Y576772D02*
G03X608268Y572835I0J-3937D01*
G01X612205Y576772D02*
X643701D01*
G01X612205D02*
G03X608268Y572835I0J-3937D01*
G01X604331Y568898D02*
G03X608268Y572835I0J3937D01*
G01X604331Y568898D02*
G03X608268Y572835I0J3937D01*
G01X612205Y576772D02*
G03X608268Y572835I0J-3937D01*
G01X612205Y576772D02*
X751969D01*
G01X608268Y588583D02*
G03X604331Y592520I-3937J0D01*
G01X608268Y588583D02*
G03X612205Y584646I3937J0D01*
G01D02*
X643701D01*
G01X608268Y588583D02*
G03X604331Y592520I-3937J0D01*
G01X608268Y588583D02*
G03X612205Y584646I3937J0D01*
G01X608268Y588583D02*
G03X604331Y592520I-3937J0D01*
G01X608268Y588583D02*
G03X612205Y584646I3937J0D01*
G01X751969D02*
X612205D01*
G01X704528Y39764D02*
G03X708465Y43701I0J3937D01*
G01X688780D02*
G03X692717Y39764I3937J0D01*
G01X678543D02*
G03X682480Y43701I0J3937D01*
G01X662795D02*
G03X666732Y39764I3937J0D01*
G01X678543D02*
X666732D01*
G01X704528D02*
X692717D01*
G01X690748Y29331D02*
G03X683268I-3740J0D01*
G01X690748Y1969D02*
Y29331D01*
G01X681299Y0D02*
X683268Y1969D01*
G01D02*
Y29331D01*
G01X690748Y1969D02*
X692717Y0D01*
G01X732874D02*
X692717D01*
G01Y59449D02*
G03X688780Y55512I0J-3937D01*
G01X708465D02*
G03X704528Y59449I-3937J0D01*
G01X682480Y55512D02*
G03X678543Y59449I-3937J0D01*
G01X666732D02*
G03X662795Y55512I0J-3937D01*
G01X708465D02*
Y43701D01*
G01X688780D02*
Y55512D01*
G01X682480D02*
Y43701D01*
G01X662795D02*
Y55512D01*
G01X692717Y59449D02*
X704528D01*
G01X666732D02*
X678543D01*
G01X697441Y114567D02*
G03Y106693I0J-3937D01*
G01X666732D02*
G03Y114567I0J3937D01*
G01X704528Y274804D02*
G03X708465Y278741I0J3937D01*
G01X688780D02*
G03X692717Y274804I3937J0D01*
G01X678543D02*
G03X682480Y278741I0J3937D01*
G01X662795D02*
G03X666732Y274804I3937J0D01*
G01X708465Y290552D02*
Y278741D01*
G01X688780D02*
Y290552D01*
G01X682480D02*
Y278741D01*
G01X662795D02*
Y290552D01*
G01X678543Y274804D02*
X666732D01*
G01X704528D02*
X692717D01*
G01X690748Y264370D02*
G03X683268I-3740J0D01*
G01X690748Y237008D02*
Y264370D01*
G01X681299Y235040D02*
X683268Y237008D01*
G01D02*
Y264370D01*
G01X690748Y237008D02*
X692717Y235040D01*
G01X732874D02*
X692717D01*
G01Y294489D02*
G03X688780Y290552I0J-3937D01*
G01X708465D02*
G03X704528Y294489I-3937J0D01*
G01X682480Y290552D02*
G03X678543Y294489I-3937J0D01*
G01X666732D02*
G03X662795Y290552I0J-3937D01*
G01X692717Y294489D02*
X704528D01*
G01X666732D02*
X678543D01*
G01X697441Y349607D02*
G03Y341733I0J-3937D01*
G01X666732D02*
G03Y349607I0J3937D01*
G01X704528Y509843D02*
G03X708465Y513780I0J3937D01*
G01X688780D02*
G03X692717Y509843I3937J0D01*
G01Y529528D02*
G03X688780Y525591I0J-3937D01*
G01X708465D02*
G03X704528Y529528I-3937J0D01*
G01X682480Y525591D02*
G03X678543Y529528I-3937J0D01*
G01Y509843D02*
G03X682480Y513780I0J3937D01*
G01X662795D02*
G03X666732Y509843I3937J0D01*
G01Y529528D02*
G03X662795Y525591I0J-3937D01*
G01X708465D02*
Y513780D01*
G01X688780D02*
Y525591D01*
G01X682480D02*
Y513780D01*
G01X662795D02*
Y525591D01*
G01X692717Y529528D02*
X704528D01*
G01X666732D02*
X678543D01*
G01Y509843D02*
X666732D01*
G01X704528D02*
X692717D01*
G01X690748Y499410D02*
G03X683268I-3740J0D01*
G01X690748Y472048D02*
Y499410D01*
G01X681299Y470079D02*
X683268Y472048D01*
G01D02*
Y499410D01*
G01X690748Y472048D02*
X692717Y470079D01*
G01X732874D02*
X692717D01*
G01X697441Y584646D02*
G03Y576772I0J-3937D01*
G01X666732D02*
G03Y584646I0J3937D01*
G01X734843Y1969D02*
Y59941D01*
G01D02*
Y33858D01*
G01X732874Y0D02*
X734843Y1969D01*
G01X762744Y17317D02*
G03I-4292J0D01*
G01X775591Y553149D02*
Y15000D01*
G01X760591Y0D02*
G03X775591Y15000I0J15000D01*
G01X742717Y0D02*
Y56004D01*
G01Y0D02*
X760591D01*
G01X755906Y102756D02*
G03X751969Y106693I-3937J0D01*
G01Y63878D02*
G03X755906Y67815I0J3937D01*
G01X738780Y63878D02*
G03X734843Y59941I0J-3937D01*
G01X755906Y102756D02*
Y67815D01*
G01X751969Y63878D02*
X738780D01*
G01X763780Y152761D02*
Y98517D01*
G01Y67822D02*
Y67803D01*
G01X751969Y56004D02*
X742717D01*
G01X751969D02*
G03X763780Y67815I0J11811D01*
G01D02*
G03X755906I-3937J0D01*
G01Y98524D02*
G03X763780I3937J0D01*
G01X751969Y114567D02*
G03X755906Y118504I0J3937D01*
G01D02*
Y183465D01*
G01X763780Y152756D02*
G03X755906I-3937J0D01*
G01Y183465D02*
G03X751969Y187402I-3937J0D01*
G01X734843Y191339D02*
G03X738780Y187402I3937J0D01*
G01X751969D02*
X738780D01*
G01X734843Y219292D02*
X732874Y221260D01*
G01X734843Y219292D02*
Y191339D01*
G01X755906Y183465D02*
G03X763780I3937J0D01*
G01Y302855D02*
Y183460D01*
G01X734843Y237008D02*
Y294981D01*
G01D02*
Y268898D01*
G01X732874Y235040D02*
X734843Y237008D01*
G01X755906Y337796D02*
G03X751969Y341733I-3937J0D01*
G01Y298918D02*
G03X755906Y302855I0J3937D01*
G01X738780Y298918D02*
G03X734843Y294981I0J-3937D01*
G01X755906Y337796D02*
Y302855D01*
G01X751969Y298918D02*
X738780D01*
G01X763780Y387796D02*
Y333559D01*
G01Y302855D02*
G03X755906I-3937J0D01*
G01Y333563D02*
G03X763780I3937J0D01*
G01X751969Y349607D02*
G03X755906Y353544I0J3937D01*
G01D02*
Y418504D01*
G01X763780Y387796D02*
G03X755906I-3937J0D01*
G01Y418504D02*
G03X751969Y422441I-3937J0D01*
G01X734843Y426378D02*
G03X738780Y422441I3937J0D01*
G01X751969D02*
X738780D01*
G01X734843Y454331D02*
X732874Y456300D01*
G01X734843Y454331D02*
Y426378D01*
G01X763780Y537894D02*
Y418504D01*
G01X755906Y418505D02*
G03X763780I3937J0D01*
G01X734843Y472048D02*
Y530020D01*
G01D02*
Y503937D01*
G01X732874Y470079D02*
X734843Y472048D01*
G01X755906Y572835D02*
G03X751969Y576772I-3937J0D01*
G01Y533957D02*
G03X755906Y537894I0J3937D01*
G01X738780Y533957D02*
G03X734843Y530020I0J-3937D01*
G01X755906Y572835D02*
Y537894D01*
G01X751969Y533957D02*
X738780D01*
G01X751969Y584646D02*
G03X755906Y588583I0J3937D01*
G01D02*
Y653544D01*
G01X775591Y561023D02*
G03Y553149I0J-3937D01*
G01X763780Y537894D02*
G03X755906I-3937J0D01*
G01Y568603D02*
G03X763780I3937J0D01*
G01X775591Y676339D02*
Y561023D01*
G01X763780Y622835D02*
Y568603D01*
G01Y622835D02*
G03X755906I-3937J0D01*
G01Y653544D02*
G03X763780I3937J0D01*
G01X755906D02*
G03X751969Y657481I-3937J0D01*
G01X734843Y661418D02*
G03X738780Y657481I3937J0D01*
G01X751969D02*
X738780D01*
G01X734843Y689371D02*
X732874Y691339D01*
G01X734843Y689371D02*
Y661418D01*
G01X760014Y677788D02*
G03I-4292J0D01*
G01X775591Y676339D02*
G03X760591Y691339I-15000J0D01*
G01X751969Y665355D02*
X742717D01*
G01X763780Y653544D02*
G03X751969Y665355I-11811J0D01*
G01X742717Y691339D02*
X760591D01*
G01X742717Y665355D02*
Y691339D01*
G54D12*
G01X192913Y58700D02*
Y12262D01*
G01X174522Y57589D02*
Y23920D01*
G01D02*
X173228Y22626D01*
G01D02*
Y12262D01*
G01X175872Y57029D02*
Y23920D01*
G01D02*
X177165Y22627D01*
G01D02*
Y12262D01*
G01X192913Y83266D02*
X192912D01*
G01D02*
X189933Y80287D01*
G01D02*
Y71300D01*
G01D02*
X193633Y67600D01*
G01D02*
Y59420D01*
G01D02*
X192913Y58700D01*
G01X173228Y91141D02*
X173227D01*
G01D02*
X172743Y90657D01*
G01D02*
Y70900D01*
G01D02*
X176493Y67150D01*
G01D02*
Y59560D01*
G01D02*
X174522Y57589D01*
G01X177168Y83266D02*
X177167D01*
G01D02*
X174093Y80192D01*
G01D02*
Y71460D01*
G01D02*
X177843Y67710D01*
G01D02*
Y59000D01*
G01D02*
X175872Y57029D01*
G01X295773Y38060D02*
X281873D01*
G01D02*
X279433Y40500D01*
G01D02*
Y59300D01*
G01X282333Y62200D02*
X300033D01*
G01X279433Y59300D02*
X282333Y62200D01*
G01X328303Y59290D02*
Y33370D01*
G01D02*
X322835Y27902D01*
G01D02*
Y12262D01*
G01X331546Y59187D02*
Y24013D01*
G01D02*
X330709Y23176D01*
G01D02*
Y12262D01*
G01X299212D02*
Y34621D01*
G01D02*
X295773Y38060D01*
G01X334646Y12262D02*
Y68287D01*
G01X310883Y34700D02*
X312733Y32850D01*
G01D02*
Y24900D01*
G01D02*
X311024Y23191D01*
G01D02*
Y12262D01*
G01X301933Y62500D02*
Y40300D01*
G01D02*
X307533Y34700D01*
G01D02*
X310883D01*
G01X322833Y91141D02*
Y72017D01*
G01D02*
X326333Y68517D01*
G01D02*
Y61260D01*
G01D02*
X328303Y59290D01*
G01X330708Y91141D02*
Y70775D01*
G01D02*
X327844Y67911D01*
G01D02*
Y62889D01*
G01D02*
X331546Y59187D01*
G01X300033Y62200D02*
X302233Y64400D01*
G01D02*
Y70519D01*
G01D02*
X297333Y75419D01*
G01D02*
Y81200D01*
G01D02*
X299212Y83079D01*
G01D02*
Y91141D01*
G01D02*
X299213D01*
G01X334646Y68287D02*
X331785Y71148D01*
G01D02*
Y80404D01*
G01D02*
X334647Y83266D01*
G01D02*
X334648D01*
G01X311023D02*
X311022D01*
G01D02*
X309488Y84800D01*
G01D02*
X302333D01*
G01D02*
X298433Y80900D01*
G01D02*
Y75800D01*
G01D02*
X304033Y70200D01*
G01D02*
Y64600D01*
G01D02*
X301933Y62500D01*
M02*
